G04*
G04 #@! TF.GenerationSoftware,Altium Limited,Altium Designer,22.4.2 (48)*
G04*
G04 Layer_Physical_Order=1*
G04 Layer_Color=255*
%FSLAX25Y25*%
%MOIN*%
G70*
G04*
G04 #@! TF.SameCoordinates,446674BB-F454-490D-8607-5140536C8ADF*
G04*
G04*
G04 #@! TF.FilePolarity,Positive*
G04*
G01*
G75*
%ADD10C,0.01000*%
%ADD18C,0.00800*%
%ADD21C,0.00500*%
%ADD26R,0.05709X0.07480*%
%ADD27R,0.07087X0.00984*%
%ADD28R,0.04331X0.04134*%
%ADD29R,0.11417X0.21260*%
%ADD30R,0.02244X0.07756*%
%ADD31R,0.02835X0.03937*%
%ADD32R,0.04528X0.05709*%
%ADD33R,0.05709X0.04528*%
%ADD34R,0.03937X0.02835*%
%ADD35R,0.03347X0.03740*%
%ADD36R,0.03937X0.03740*%
%ADD37R,0.12362X0.06063*%
%ADD38R,0.05315X0.06693*%
%ADD39R,0.00984X0.06102*%
%ADD40R,0.06693X0.05315*%
%ADD41R,0.06102X0.00984*%
%ADD42R,0.06650X0.04400*%
%ADD43R,0.05000X0.20000*%
%ADD44R,0.02756X0.03543*%
%ADD45R,0.03740X0.05709*%
%ADD46R,0.05709X0.03740*%
%ADD47R,0.03543X0.01968*%
%ADD48R,0.01968X0.03543*%
%ADD49R,0.03347X0.01181*%
%ADD50R,0.08287X0.04409*%
%ADD51R,0.03150X0.03150*%
%ADD52R,0.03740X0.03150*%
%ADD53R,0.03543X0.01024*%
%ADD54R,0.01024X0.03543*%
%ADD55R,0.12795X0.12795*%
%ADD56R,0.03543X0.02362*%
%ADD57R,0.02165X0.02362*%
%ADD58R,0.03150X0.03543*%
%ADD59R,0.03740X0.03740*%
%ADD60R,0.03543X0.02953*%
%ADD61R,0.08661X0.04134*%
%ADD62R,0.04134X0.03937*%
%ADD63R,0.03740X0.03740*%
%ADD64R,0.04134X0.04331*%
%ADD65R,0.02953X0.03347*%
%ADD66R,0.03937X0.04921*%
%ADD67R,0.04921X0.03937*%
%ADD68R,0.05512X0.05512*%
%ADD69R,0.03937X0.05512*%
%ADD70R,0.02362X0.03150*%
%ADD71R,0.02362X0.02559*%
%ADD72R,0.02800X0.16500*%
%ADD73R,0.02800X0.12600*%
%ADD74O,0.08661X0.02362*%
%ADD75O,0.07480X0.02362*%
%ADD76R,0.02657X0.00984*%
%ADD77R,0.00984X0.02657*%
%ADD78R,0.01968X0.01378*%
G04:AMPARAMS|DCode=79|XSize=40.88mil|YSize=20.95mil|CornerRadius=10.48mil|HoleSize=0mil|Usage=FLASHONLY|Rotation=270.000|XOffset=0mil|YOffset=0mil|HoleType=Round|Shape=RoundedRectangle|*
%AMROUNDEDRECTD79*
21,1,0.04088,0.00000,0,0,270.0*
21,1,0.01993,0.02095,0,0,270.0*
1,1,0.02095,0.00000,-0.00996*
1,1,0.02095,0.00000,0.00996*
1,1,0.02095,0.00000,0.00996*
1,1,0.02095,0.00000,-0.00996*
%
%ADD79ROUNDEDRECTD79*%
%ADD80R,0.02095X0.04088*%
%ADD81R,0.03740X0.03937*%
%ADD82R,0.03937X0.03347*%
%ADD83R,0.03543X0.02756*%
%ADD149C,0.02000*%
%ADD150C,0.04000*%
%ADD151C,0.03000*%
%ADD152C,0.02500*%
%ADD153C,0.01200*%
%ADD154R,0.09478X0.29380*%
%ADD155R,0.09941X0.06791*%
%ADD156R,0.11043X0.06693*%
%ADD157C,0.05906*%
%ADD158R,0.05906X0.05906*%
%ADD159C,0.07500*%
%ADD160C,0.05000*%
%ADD161C,0.09843*%
%ADD162C,0.02166*%
%ADD163C,0.06598*%
%ADD164C,0.08661*%
%ADD165R,0.07874X0.07874*%
%ADD166C,0.25000*%
%ADD167C,0.01600*%
%ADD168C,0.03200*%
%ADD169C,0.01400*%
%ADD170C,0.20000*%
%ADD171C,0.01968*%
G36*
X338189Y-129528D02*
X329528D01*
Y-118110D01*
X338189D01*
Y-129528D01*
D02*
G37*
G36*
X377953Y-129921D02*
X368504D01*
Y-118504D01*
X377953D01*
Y-129921D01*
D02*
G37*
G36*
X322515Y-226403D02*
X322463Y-226456D01*
X322219Y-227044D01*
Y-227680D01*
X322463Y-228269D01*
X322515Y-228321D01*
Y-230340D01*
X322463Y-230393D01*
X322219Y-230981D01*
Y-231617D01*
X322463Y-232206D01*
X322515Y-232258D01*
Y-236277D01*
X322494Y-236298D01*
X322250Y-236887D01*
Y-237523D01*
X322494Y-238111D01*
X322515Y-238132D01*
Y-240246D01*
X322494Y-240267D01*
X322250Y-240855D01*
Y-241492D01*
X322494Y-242080D01*
X322515Y-242101D01*
Y-271234D01*
X321873D01*
X321773Y-271133D01*
X321184Y-270890D01*
X320548D01*
X319960Y-271133D01*
X319510Y-271583D01*
X319266Y-272171D01*
Y-272808D01*
X319510Y-273396D01*
X319960Y-273846D01*
X320548Y-274090D01*
X321184D01*
X321773Y-273846D01*
X321937Y-273681D01*
X322515D01*
Y-336022D01*
X122712D01*
Y-136219D01*
X268103D01*
X268486Y-136718D01*
X268461Y-136843D01*
X268555Y-137311D01*
X268820Y-137708D01*
X269217Y-137973D01*
X269685Y-138066D01*
X270153Y-137973D01*
X270550Y-137708D01*
X270703Y-137555D01*
X270969Y-137158D01*
X271062Y-136689D01*
Y-136219D01*
X322515D01*
Y-226403D01*
D02*
G37*
G36*
X73902Y-135327D02*
X76772D01*
Y-135827D01*
X77272D01*
Y-138697D01*
X79642D01*
Y-138697D01*
X80007Y-138497D01*
X85347D01*
Y-135241D01*
X85531Y-135102D01*
X86031Y-135351D01*
Y-138589D01*
X85898Y-138722D01*
X85654Y-139310D01*
Y-139947D01*
X85898Y-140535D01*
X86348Y-140985D01*
X86936Y-141229D01*
X87572D01*
X88136Y-140995D01*
X88210Y-141176D01*
X88661Y-141627D01*
X89249Y-141870D01*
X89885D01*
X90051Y-141801D01*
X90551Y-142135D01*
Y-159964D01*
X90051Y-160171D01*
X87479Y-157599D01*
X87082Y-157334D01*
X86614Y-157241D01*
X83677D01*
Y-156996D01*
X81004D01*
Y-156496D01*
X80504D01*
Y-154905D01*
X78331D01*
Y-155171D01*
X77321D01*
X73176Y-151026D01*
Y-148858D01*
X73376Y-148657D01*
X73592Y-148138D01*
X70109D01*
X70324Y-148657D01*
X70525Y-148858D01*
Y-151575D01*
X70626Y-152082D01*
X70913Y-152512D01*
X75834Y-157433D01*
X76264Y-157721D01*
X76772Y-157822D01*
X78331D01*
Y-158087D01*
X78531D01*
Y-161259D01*
X78223Y-161320D01*
X77826Y-161585D01*
X76891Y-162521D01*
X76626Y-162918D01*
X76532Y-163386D01*
Y-165817D01*
X76032Y-166169D01*
X76027Y-166167D01*
Y-162402D01*
X75933Y-161933D01*
X75668Y-161536D01*
X73700Y-159568D01*
X73303Y-159303D01*
X72835Y-159210D01*
X71076D01*
Y-155105D01*
X66129D01*
Y-155273D01*
X65945D01*
X65477Y-155366D01*
X65080Y-155631D01*
X64454Y-156257D01*
X62020D01*
Y-154909D01*
X57665D01*
Y-160052D01*
X62020D01*
Y-158704D01*
X64454D01*
X65080Y-159330D01*
X65477Y-159595D01*
X65945Y-159688D01*
X66129D01*
Y-163792D01*
X70525D01*
Y-165101D01*
X69004Y-166621D01*
X64948D01*
Y-168163D01*
X64764D01*
X64257Y-168264D01*
X63827Y-168551D01*
X63039Y-169338D01*
X62752Y-169768D01*
X62651Y-170276D01*
Y-178197D01*
X62620Y-178227D01*
X62376Y-178816D01*
Y-179452D01*
X62620Y-180040D01*
X63070Y-180490D01*
X63658Y-180734D01*
X64295D01*
X64883Y-180490D01*
X65333Y-180040D01*
X65576Y-179452D01*
Y-178816D01*
X65473Y-178567D01*
X65807Y-178067D01*
X66690D01*
Y-178444D01*
X66765Y-178821D01*
X70315D01*
X70209Y-178567D01*
X70518Y-178067D01*
X71079D01*
Y-175500D01*
X67913D01*
Y-174500D01*
X71079D01*
Y-171933D01*
X70879D01*
Y-168496D01*
X71671Y-167703D01*
X72133Y-167895D01*
Y-171961D01*
X76914D01*
X77080Y-172244D01*
X76914Y-172527D01*
X72133D01*
Y-177867D01*
X73100D01*
X73206Y-177977D01*
X73389Y-178367D01*
X73203Y-178816D01*
Y-179452D01*
X73447Y-180040D01*
X73897Y-180490D01*
X74485Y-180734D01*
X75121D01*
X75709Y-180490D01*
X76160Y-180040D01*
X76403Y-179452D01*
Y-178816D01*
X76217Y-178367D01*
X76401Y-177977D01*
X76506Y-177867D01*
X77108D01*
X77517Y-178150D01*
X77553Y-178334D01*
X77610Y-178618D01*
X77875Y-179015D01*
X79109Y-180248D01*
Y-180436D01*
X79352Y-181024D01*
X79802Y-181474D01*
X80390Y-181718D01*
X81027D01*
X81615Y-181474D01*
X82065Y-181024D01*
X82309Y-180436D01*
Y-179800D01*
X82065Y-179212D01*
X81615Y-178762D01*
X81088Y-178543D01*
X80987Y-178446D01*
X80943Y-178367D01*
X81237Y-177867D01*
X85347D01*
Y-176900D01*
X85457Y-176795D01*
X85847Y-176611D01*
X86296Y-176797D01*
X86932D01*
X87520Y-176553D01*
X87971Y-176103D01*
X88214Y-175515D01*
Y-174879D01*
X87971Y-174291D01*
X87520Y-173840D01*
X86932Y-173597D01*
X86296D01*
X85847Y-173783D01*
X85457Y-173599D01*
X85347Y-173494D01*
Y-172527D01*
X80566D01*
X80401Y-172244D01*
X80566Y-171961D01*
X85347D01*
Y-170985D01*
X85388Y-170936D01*
X85847Y-170693D01*
X86244Y-170857D01*
X86880D01*
X87469Y-170613D01*
X87919Y-170163D01*
X88162Y-169575D01*
Y-168939D01*
X87919Y-168351D01*
X87846Y-168278D01*
X87943Y-167787D01*
X88074Y-167733D01*
X88371Y-167436D01*
X88661Y-167727D01*
X89249Y-167970D01*
X89885D01*
X90051Y-167901D01*
X90551Y-168236D01*
Y-235945D01*
X90165Y-236262D01*
X90041Y-236237D01*
X78898D01*
X78740Y-236206D01*
X78038Y-236345D01*
X77442Y-236743D01*
X77045Y-237339D01*
X76905Y-238041D01*
X77045Y-238743D01*
X77442Y-239339D01*
X77474Y-239370D01*
X78069Y-239768D01*
X78772Y-239908D01*
X89281D01*
X90551Y-241178D01*
Y-354331D01*
X-27320D01*
Y-317092D01*
X-26820Y-316885D01*
X-26579Y-317126D01*
X-26059Y-317341D01*
Y-315600D01*
Y-313859D01*
X-26579Y-314074D01*
X-26820Y-314315D01*
X-27320Y-314108D01*
Y-301092D01*
X-26820Y-300885D01*
X-26579Y-301126D01*
X-26059Y-301341D01*
Y-299600D01*
Y-297859D01*
X-26579Y-298074D01*
X-26820Y-298315D01*
X-27320Y-298108D01*
Y-269092D01*
X-26820Y-268885D01*
X-26579Y-269126D01*
X-26059Y-269341D01*
Y-267600D01*
Y-265859D01*
X-26579Y-266074D01*
X-26820Y-266315D01*
X-27320Y-266108D01*
Y-261092D01*
X-26820Y-260885D01*
X-26579Y-261126D01*
X-26059Y-261341D01*
Y-259600D01*
Y-257859D01*
X-26579Y-258074D01*
X-26820Y-258315D01*
X-27320Y-258108D01*
Y-213092D01*
X-26820Y-212885D01*
X-26579Y-213126D01*
X-26059Y-213341D01*
Y-211600D01*
Y-209859D01*
X-26579Y-210074D01*
X-26820Y-210315D01*
X-27320Y-210108D01*
Y-157092D01*
X-26820Y-156885D01*
X-26579Y-157126D01*
X-26059Y-157341D01*
Y-155600D01*
Y-153859D01*
X-26579Y-154074D01*
X-26820Y-154315D01*
X-27320Y-154108D01*
Y-141092D01*
X-26820Y-140885D01*
X-26579Y-141126D01*
X-26059Y-141341D01*
Y-139600D01*
Y-137859D01*
X-26579Y-138074D01*
X-26820Y-138315D01*
X-27320Y-138108D01*
Y-133858D01*
X73902D01*
Y-135327D01*
D02*
G37*
G36*
X361811Y-141732D02*
X344882D01*
Y-103543D01*
X361811D01*
Y-141732D01*
D02*
G37*
G36*
X383071Y-144882D02*
X369291D01*
Y-132677D01*
X383071D01*
Y-144882D01*
D02*
G37*
G36*
X603543Y-147244D02*
X570866D01*
Y-140551D01*
X603543D01*
Y-147244D01*
D02*
G37*
G36*
X619291Y-146850D02*
X616535D01*
Y-183858D01*
X596063D01*
Y-159843D01*
X607087D01*
Y-137795D01*
X577953D01*
Y-123228D01*
X619291D01*
Y-146850D01*
D02*
G37*
G36*
X678740Y-216929D02*
X652362D01*
Y-205906D01*
X678740D01*
Y-216929D01*
D02*
G37*
G36*
X652756Y-235433D02*
X642126D01*
Y-237402D01*
X636221D01*
Y-228346D01*
X652756D01*
Y-235433D01*
D02*
G37*
G36*
X632283Y-232038D02*
Y-240551D01*
X585285D01*
X582497Y-237763D01*
X582567Y-237412D01*
X582443Y-236788D01*
X582261Y-236516D01*
Y-235446D01*
X584904D01*
Y-231011D01*
X579380D01*
Y-230013D01*
X584904D01*
Y-225578D01*
X579380D01*
Y-219794D01*
X579650Y-219406D01*
X585187D01*
Y-214972D01*
X579650D01*
X579380Y-214584D01*
Y-212598D01*
X612844D01*
X632283Y-232038D01*
D02*
G37*
G36*
X678740Y-266535D02*
X666535D01*
Y-260630D01*
X659055D01*
Y-265354D01*
X651968D01*
Y-253937D01*
X653150D01*
Y-246457D01*
X666929D01*
Y-237795D01*
X678740D01*
Y-266535D01*
D02*
G37*
G36*
X649606Y-250787D02*
Y-252362D01*
X644488D01*
Y-266535D01*
X636221D01*
Y-240945D01*
X649606D01*
Y-250787D01*
D02*
G37*
G36*
X678740Y-307480D02*
X659449D01*
Y-291339D01*
X666929D01*
Y-287008D01*
X678740D01*
Y-307480D01*
D02*
G37*
%LPC*%
G36*
X143119Y-152143D02*
X141921D01*
X140763Y-152453D01*
X139726Y-153052D01*
X138879Y-153899D01*
X138280Y-154937D01*
X137970Y-156094D01*
Y-157292D01*
X138280Y-158449D01*
X138879Y-159487D01*
X139726Y-160334D01*
X140763Y-160933D01*
X141921Y-161243D01*
X143119D01*
X144276Y-160933D01*
X145313Y-160334D01*
X146161Y-159487D01*
X146760Y-158449D01*
X147070Y-157292D01*
Y-156094D01*
X146760Y-154937D01*
X146161Y-153899D01*
X145313Y-153052D01*
X144276Y-152453D01*
X143119Y-152143D01*
D02*
G37*
G36*
X303545Y-149234D02*
X302105D01*
X300692Y-149515D01*
X299362Y-150066D01*
X298165Y-150866D01*
X297146Y-151885D01*
X296346Y-153082D01*
X295795Y-154412D01*
X295514Y-155825D01*
Y-157265D01*
X295795Y-158677D01*
X296346Y-160008D01*
X297146Y-161205D01*
X298165Y-162223D01*
X299362Y-163023D01*
X300692Y-163575D01*
X302105Y-163856D01*
X303545D01*
X304957Y-163575D01*
X306288Y-163023D01*
X307485Y-162223D01*
X308503Y-161205D01*
X309303Y-160008D01*
X309855Y-158677D01*
X310135Y-157265D01*
Y-155825D01*
X309855Y-154412D01*
X309303Y-153082D01*
X308503Y-151885D01*
X307485Y-150866D01*
X306288Y-150066D01*
X304957Y-149515D01*
X303545Y-149234D01*
D02*
G37*
G36*
X316407Y-216339D02*
X286880D01*
Y-227786D01*
X286833Y-227834D01*
X286589Y-228422D01*
Y-229058D01*
X286833Y-229646D01*
X286880Y-229694D01*
Y-230149D01*
X286833Y-230196D01*
X286589Y-230784D01*
Y-231421D01*
X286833Y-232009D01*
X286880Y-232056D01*
Y-232392D01*
X286701Y-232572D01*
X286457Y-233160D01*
Y-233796D01*
X286701Y-234384D01*
X286880Y-234563D01*
X286880Y-241247D01*
X286810Y-241351D01*
X286717Y-241819D01*
X286810Y-242287D01*
X286880Y-242391D01*
Y-244010D01*
X286701Y-244189D01*
X286457Y-244777D01*
Y-245413D01*
X286701Y-246001D01*
X286880Y-246180D01*
Y-246684D01*
X286833Y-246731D01*
X286589Y-247320D01*
Y-247956D01*
X286833Y-248544D01*
X286880Y-248591D01*
Y-255709D01*
X316407D01*
X316407Y-231716D01*
X316583Y-231541D01*
X316826Y-230953D01*
Y-230316D01*
X316583Y-229728D01*
X316407Y-229553D01*
Y-228453D01*
X316464Y-228316D01*
Y-227679D01*
X316407Y-227541D01*
Y-216339D01*
D02*
G37*
G36*
X143702Y-309077D02*
X142262D01*
X140850Y-309358D01*
X139519Y-309909D01*
X138322Y-310709D01*
X137304Y-311727D01*
X136504Y-312925D01*
X135952Y-314255D01*
X135672Y-315667D01*
Y-317107D01*
X135952Y-318520D01*
X136504Y-319850D01*
X137304Y-321048D01*
X138322Y-322066D01*
X139519Y-322866D01*
X140850Y-323417D01*
X142262Y-323698D01*
X143702D01*
X145115Y-323417D01*
X146445Y-322866D01*
X147643Y-322066D01*
X148661Y-321048D01*
X149461Y-319850D01*
X150012Y-318520D01*
X150293Y-317107D01*
Y-315667D01*
X150012Y-314255D01*
X149461Y-312925D01*
X148661Y-311727D01*
X147643Y-310709D01*
X146445Y-309909D01*
X145115Y-309358D01*
X143702Y-309077D01*
D02*
G37*
G36*
X303545D02*
X302105D01*
X300692Y-309358D01*
X299362Y-309909D01*
X298165Y-310709D01*
X298046Y-310827D01*
X239636D01*
Y-334449D01*
X308533D01*
Y-321003D01*
X309303Y-319850D01*
X309855Y-318520D01*
X310135Y-317107D01*
Y-315667D01*
X309855Y-314255D01*
X309303Y-312925D01*
X308533Y-311772D01*
Y-310827D01*
X307603D01*
X307485Y-310709D01*
X306288Y-309909D01*
X304957Y-309358D01*
X303545Y-309077D01*
D02*
G37*
G36*
X76272Y-136327D02*
X73902D01*
Y-138697D01*
X76272D01*
Y-136327D01*
D02*
G37*
G36*
X41941Y-137859D02*
X41421Y-138074D01*
X40915Y-138580D01*
X40703Y-139092D01*
X40179D01*
X39967Y-138580D01*
X39461Y-138074D01*
X38941Y-137859D01*
Y-139600D01*
Y-141341D01*
X39461Y-141126D01*
X39967Y-140620D01*
X40179Y-140108D01*
X40703D01*
X40915Y-140620D01*
X41421Y-141126D01*
X41941Y-141341D01*
Y-139600D01*
Y-137859D01*
D02*
G37*
G36*
X37941D02*
X37421Y-138074D01*
X36915Y-138580D01*
X36703Y-139092D01*
X36179D01*
X35967Y-138580D01*
X35461Y-138074D01*
X34941Y-137859D01*
Y-139600D01*
Y-141341D01*
X35461Y-141126D01*
X35967Y-140620D01*
X36179Y-140108D01*
X36703D01*
X36915Y-140620D01*
X37421Y-141126D01*
X37941Y-141341D01*
Y-139600D01*
Y-137859D01*
D02*
G37*
G36*
X33941D02*
X33421Y-138074D01*
X32915Y-138580D01*
X32703Y-139092D01*
X32179D01*
X31967Y-138580D01*
X31461Y-138074D01*
X30941Y-137859D01*
Y-139600D01*
Y-141341D01*
X31461Y-141126D01*
X31967Y-140620D01*
X32179Y-140108D01*
X32703D01*
X32915Y-140620D01*
X33421Y-141126D01*
X33941Y-141341D01*
Y-139600D01*
Y-137859D01*
D02*
G37*
G36*
X29941D02*
X29421Y-138074D01*
X28915Y-138580D01*
X28703Y-139092D01*
X28179D01*
X27967Y-138580D01*
X27461Y-138074D01*
X26941Y-137859D01*
Y-139600D01*
Y-141341D01*
X27461Y-141126D01*
X27967Y-140620D01*
X28179Y-140108D01*
X28703D01*
X28915Y-140620D01*
X29421Y-141126D01*
X29941Y-141341D01*
Y-139600D01*
Y-137859D01*
D02*
G37*
G36*
X25941D02*
X25421Y-138074D01*
X24915Y-138580D01*
X24703Y-139092D01*
X24179D01*
X23967Y-138580D01*
X23461Y-138074D01*
X22941Y-137859D01*
Y-139600D01*
Y-141341D01*
X23461Y-141126D01*
X23967Y-140620D01*
X24179Y-140108D01*
X24703D01*
X24915Y-140620D01*
X25421Y-141126D01*
X25941Y-141341D01*
Y-139600D01*
Y-137859D01*
D02*
G37*
G36*
X21941D02*
X21421Y-138074D01*
X20915Y-138580D01*
X20703Y-139092D01*
X20179D01*
X19967Y-138580D01*
X19461Y-138074D01*
X18941Y-137859D01*
Y-139600D01*
Y-141341D01*
X19461Y-141126D01*
X19967Y-140620D01*
X20179Y-140108D01*
X20703D01*
X20915Y-140620D01*
X21421Y-141126D01*
X21941Y-141341D01*
Y-139600D01*
Y-137859D01*
D02*
G37*
G36*
X17941D02*
X17421Y-138074D01*
X16915Y-138580D01*
X16703Y-139092D01*
X16179D01*
X15967Y-138580D01*
X15461Y-138074D01*
X14941Y-137859D01*
Y-139600D01*
Y-141341D01*
X15461Y-141126D01*
X15967Y-140620D01*
X16179Y-140108D01*
X16703D01*
X16915Y-140620D01*
X17421Y-141126D01*
X17941Y-141341D01*
Y-139600D01*
Y-137859D01*
D02*
G37*
G36*
X13941D02*
X13421Y-138074D01*
X12915Y-138580D01*
X12703Y-139092D01*
X12179D01*
X11967Y-138580D01*
X11461Y-138074D01*
X10941Y-137859D01*
Y-139600D01*
Y-141341D01*
X11461Y-141126D01*
X11967Y-140620D01*
X12179Y-140108D01*
X12703D01*
X12915Y-140620D01*
X13421Y-141126D01*
X13941Y-141341D01*
Y-139600D01*
Y-137859D01*
D02*
G37*
G36*
X9941D02*
X9421Y-138074D01*
X8915Y-138580D01*
X8703Y-139092D01*
X8179D01*
X7967Y-138580D01*
X7461Y-138074D01*
X6941Y-137859D01*
Y-139600D01*
Y-141341D01*
X7461Y-141126D01*
X7967Y-140620D01*
X8179Y-140108D01*
X8703D01*
X8915Y-140620D01*
X9421Y-141126D01*
X9941Y-141341D01*
Y-139600D01*
Y-137859D01*
D02*
G37*
G36*
X-6059D02*
X-6579Y-138074D01*
X-7085Y-138580D01*
X-7297Y-139092D01*
X-7821D01*
X-8033Y-138580D01*
X-8539Y-138074D01*
X-9059Y-137859D01*
Y-139600D01*
Y-141341D01*
X-8539Y-141126D01*
X-8033Y-140620D01*
X-7821Y-140108D01*
X-7297D01*
X-7085Y-140620D01*
X-6579Y-141126D01*
X-6059Y-141341D01*
Y-139600D01*
Y-137859D01*
D02*
G37*
G36*
X-10059D02*
X-10579Y-138074D01*
X-11085Y-138580D01*
X-11297Y-139092D01*
X-11821D01*
X-12033Y-138580D01*
X-12539Y-138074D01*
X-13059Y-137859D01*
Y-139600D01*
Y-141341D01*
X-12539Y-141126D01*
X-12033Y-140620D01*
X-11821Y-140108D01*
X-11297D01*
X-11085Y-140620D01*
X-10579Y-141126D01*
X-10059Y-141341D01*
Y-139600D01*
Y-137859D01*
D02*
G37*
G36*
X53941D02*
X53421Y-138074D01*
X52915Y-138580D01*
X52703Y-139092D01*
X52179D01*
X51967Y-138580D01*
X51461Y-138074D01*
X50941Y-137859D01*
Y-139600D01*
Y-141341D01*
X51461Y-141126D01*
X51967Y-140620D01*
X52179Y-140108D01*
X52703D01*
X52915Y-140620D01*
X53421Y-141126D01*
X53941Y-141341D01*
Y-139600D01*
Y-137859D01*
D02*
G37*
G36*
X49941D02*
X49421Y-138074D01*
X48915Y-138580D01*
X48703Y-139092D01*
X48179D01*
X47967Y-138580D01*
X47461Y-138074D01*
X46941Y-137859D01*
Y-139600D01*
Y-141341D01*
X47461Y-141126D01*
X47967Y-140620D01*
X48179Y-140108D01*
X48703D01*
X48915Y-140620D01*
X49421Y-141126D01*
X49941Y-141341D01*
Y-139600D01*
Y-137859D01*
D02*
G37*
G36*
X45941D02*
X45421Y-138074D01*
X44915Y-138580D01*
X44703Y-139092D01*
X44179D01*
X43967Y-138580D01*
X43461Y-138074D01*
X42941Y-137859D01*
Y-139600D01*
Y-141341D01*
X43461Y-141126D01*
X43967Y-140620D01*
X44179Y-140108D01*
X44703D01*
X44915Y-140620D01*
X45421Y-141126D01*
X45941Y-141341D01*
Y-139600D01*
Y-137859D01*
D02*
G37*
G36*
X54941D02*
Y-139100D01*
X56182D01*
X55967Y-138580D01*
X55461Y-138074D01*
X54941Y-137859D01*
D02*
G37*
G36*
X5941D02*
X5421Y-138074D01*
X4915Y-138580D01*
X4700Y-139100D01*
X5941D01*
Y-137859D01*
D02*
G37*
G36*
X-5059D02*
Y-139100D01*
X-3818D01*
X-4033Y-138580D01*
X-4539Y-138074D01*
X-5059Y-137859D01*
D02*
G37*
G36*
X-14059D02*
X-14579Y-138074D01*
X-15085Y-138580D01*
X-15300Y-139100D01*
X-14059D01*
Y-137859D01*
D02*
G37*
G36*
X-25059D02*
Y-139100D01*
X-23818D01*
X-24033Y-138580D01*
X-24539Y-138074D01*
X-25059Y-137859D01*
D02*
G37*
G36*
X56182Y-140100D02*
X54941D01*
Y-141341D01*
X55461Y-141126D01*
X55967Y-140620D01*
X56182Y-140100D01*
D02*
G37*
G36*
X5941D02*
X4700D01*
X4915Y-140620D01*
X5421Y-141126D01*
X5941Y-141341D01*
Y-140100D01*
D02*
G37*
G36*
X-3818D02*
X-5059D01*
Y-141341D01*
X-4539Y-141126D01*
X-4033Y-140620D01*
X-3818Y-140100D01*
D02*
G37*
G36*
X-14059D02*
X-15300D01*
X-15085Y-140620D01*
X-14579Y-141126D01*
X-14059Y-141341D01*
Y-140100D01*
D02*
G37*
G36*
X-23818D02*
X-25059D01*
Y-141341D01*
X-24539Y-141126D01*
X-24033Y-140620D01*
X-23818Y-140100D01*
D02*
G37*
G36*
X39941Y-141859D02*
X39421Y-142074D01*
X38915Y-142580D01*
X38703Y-143092D01*
X38179D01*
X37967Y-142580D01*
X37461Y-142074D01*
X36941Y-141859D01*
Y-143600D01*
Y-145341D01*
X37461Y-145126D01*
X37967Y-144620D01*
X38179Y-144108D01*
X38703D01*
X38915Y-144620D01*
X39421Y-145126D01*
X39941Y-145341D01*
Y-143600D01*
Y-141859D01*
D02*
G37*
G36*
X35941D02*
X35421Y-142074D01*
X34915Y-142580D01*
X34703Y-143092D01*
X34179D01*
X33967Y-142580D01*
X33461Y-142074D01*
X32941Y-141859D01*
Y-143600D01*
Y-145341D01*
X33461Y-145126D01*
X33967Y-144620D01*
X34179Y-144108D01*
X34703D01*
X34915Y-144620D01*
X35421Y-145126D01*
X35941Y-145341D01*
Y-143600D01*
Y-141859D01*
D02*
G37*
G36*
X31941D02*
X31421Y-142074D01*
X30915Y-142580D01*
X30703Y-143092D01*
X30179D01*
X29967Y-142580D01*
X29461Y-142074D01*
X28941Y-141859D01*
Y-143600D01*
Y-145341D01*
X29461Y-145126D01*
X29967Y-144620D01*
X30179Y-144108D01*
X30703D01*
X30915Y-144620D01*
X31421Y-145126D01*
X31941Y-145341D01*
Y-143600D01*
Y-141859D01*
D02*
G37*
G36*
X27941D02*
X27421Y-142074D01*
X26915Y-142580D01*
X26703Y-143092D01*
X26179D01*
X25967Y-142580D01*
X25461Y-142074D01*
X24941Y-141859D01*
Y-143600D01*
Y-145341D01*
X25461Y-145126D01*
X25967Y-144620D01*
X26179Y-144108D01*
X26703D01*
X26915Y-144620D01*
X27421Y-145126D01*
X27941Y-145341D01*
Y-143600D01*
Y-141859D01*
D02*
G37*
G36*
X23941D02*
X23421Y-142074D01*
X22915Y-142580D01*
X22703Y-143092D01*
X22179D01*
X21967Y-142580D01*
X21461Y-142074D01*
X20941Y-141859D01*
Y-143600D01*
Y-145341D01*
X21461Y-145126D01*
X21967Y-144620D01*
X22179Y-144108D01*
X22703D01*
X22915Y-144620D01*
X23421Y-145126D01*
X23941Y-145341D01*
Y-143600D01*
Y-141859D01*
D02*
G37*
G36*
X19941D02*
X19421Y-142074D01*
X18915Y-142580D01*
X18703Y-143092D01*
X18179D01*
X17967Y-142580D01*
X17461Y-142074D01*
X16941Y-141859D01*
Y-143600D01*
Y-145341D01*
X17461Y-145126D01*
X17967Y-144620D01*
X18179Y-144108D01*
X18703D01*
X18915Y-144620D01*
X19421Y-145126D01*
X19941Y-145341D01*
Y-143600D01*
Y-141859D01*
D02*
G37*
G36*
X15941D02*
X15421Y-142074D01*
X14915Y-142580D01*
X14703Y-143092D01*
X14179D01*
X13967Y-142580D01*
X13461Y-142074D01*
X12941Y-141859D01*
Y-143600D01*
Y-145341D01*
X13461Y-145126D01*
X13967Y-144620D01*
X14179Y-144108D01*
X14703D01*
X14915Y-144620D01*
X15421Y-145126D01*
X15941Y-145341D01*
Y-143600D01*
Y-141859D01*
D02*
G37*
G36*
X55941D02*
X55421Y-142074D01*
X54915Y-142580D01*
X54703Y-143092D01*
X54179D01*
X53967Y-142580D01*
X53461Y-142074D01*
X52941Y-141859D01*
Y-143600D01*
Y-145341D01*
X53461Y-145126D01*
X53967Y-144620D01*
X54179Y-144108D01*
X54703D01*
X54915Y-144620D01*
X55421Y-145126D01*
X55941Y-145341D01*
Y-143600D01*
Y-141859D01*
D02*
G37*
G36*
X51941D02*
X51421Y-142074D01*
X50915Y-142580D01*
X50703Y-143092D01*
X50179D01*
X49967Y-142580D01*
X49461Y-142074D01*
X48941Y-141859D01*
Y-143600D01*
Y-145341D01*
X49461Y-145126D01*
X49967Y-144620D01*
X50179Y-144108D01*
X50703D01*
X50915Y-144620D01*
X51421Y-145126D01*
X51941Y-145341D01*
Y-143600D01*
Y-141859D01*
D02*
G37*
G36*
X47941D02*
X47421Y-142074D01*
X46915Y-142580D01*
X46703Y-143092D01*
X46179D01*
X45967Y-142580D01*
X45461Y-142074D01*
X44941Y-141859D01*
Y-143600D01*
X43941D01*
Y-141859D01*
X43421Y-142074D01*
X42915Y-142580D01*
X42703Y-143092D01*
X42179D01*
X41967Y-142580D01*
X41461Y-142074D01*
X40941Y-141859D01*
Y-143600D01*
Y-145341D01*
X41461Y-145126D01*
X41967Y-144620D01*
X42179Y-144108D01*
X42703D01*
X42915Y-144620D01*
X43421Y-145126D01*
X43933Y-145338D01*
X43933Y-145688D01*
X43883Y-145859D01*
X43272Y-146112D01*
X42765Y-146618D01*
X42550Y-147138D01*
X46033D01*
X45817Y-146618D01*
X45311Y-146112D01*
X44799Y-145900D01*
X44799Y-145550D01*
X44849Y-145379D01*
X45461Y-145126D01*
X45967Y-144620D01*
X46179Y-144108D01*
X46703D01*
X46915Y-144620D01*
X47421Y-145126D01*
X47941Y-145341D01*
Y-143600D01*
Y-141859D01*
D02*
G37*
G36*
X56941D02*
Y-143100D01*
X58182D01*
X57967Y-142580D01*
X57461Y-142074D01*
X56941Y-141859D01*
D02*
G37*
G36*
X11941D02*
X11421Y-142074D01*
X10915Y-142580D01*
X10700Y-143100D01*
X11941D01*
Y-141859D01*
D02*
G37*
G36*
X-7059D02*
Y-143100D01*
X-5818D01*
X-6033Y-142580D01*
X-6539Y-142074D01*
X-7059Y-141859D01*
D02*
G37*
G36*
X-8059D02*
X-8579Y-142074D01*
X-9085Y-142580D01*
X-9300Y-143100D01*
X-8059D01*
Y-141859D01*
D02*
G37*
G36*
X58182Y-144100D02*
X56941D01*
Y-145341D01*
X57461Y-145126D01*
X57967Y-144620D01*
X58182Y-144100D01*
D02*
G37*
G36*
X11941D02*
X10700D01*
X10915Y-144620D01*
X11421Y-145126D01*
X11941Y-145341D01*
Y-144100D01*
D02*
G37*
G36*
X-5818D02*
X-7059D01*
Y-145341D01*
X-6539Y-145126D01*
X-6033Y-144620D01*
X-5818Y-144100D01*
D02*
G37*
G36*
X-8059D02*
X-9300D01*
X-9085Y-144620D01*
X-8579Y-145126D01*
X-8059Y-145341D01*
Y-144100D01*
D02*
G37*
G36*
X2237Y-142002D02*
X2035D01*
Y-146832D01*
X6866D01*
Y-146631D01*
X6503Y-145275D01*
X5801Y-144059D01*
X4809Y-143067D01*
X3593Y-142365D01*
X2237Y-142002D01*
D02*
G37*
G36*
X-17763D02*
X-17965D01*
Y-146832D01*
X-13134D01*
Y-146631D01*
X-13497Y-145275D01*
X-14199Y-144059D01*
X-15191Y-143067D01*
X-16407Y-142365D01*
X-17763Y-142002D01*
D02*
G37*
G36*
X1035D02*
X834D01*
X-522Y-142365D01*
X-1738Y-143067D01*
X-2730Y-144059D01*
X-3432Y-145275D01*
X-3795Y-146631D01*
Y-146832D01*
X1035D01*
Y-142002D01*
D02*
G37*
G36*
X-18965D02*
X-19166D01*
X-20522Y-142365D01*
X-21738Y-143067D01*
X-22730Y-144059D01*
X-23432Y-145275D01*
X-23795Y-146631D01*
Y-146832D01*
X-18965D01*
Y-142002D01*
D02*
G37*
G36*
X33941Y-145859D02*
X33421Y-146074D01*
X32915Y-146580D01*
X32703Y-147092D01*
X32179D01*
X31967Y-146580D01*
X31461Y-146074D01*
X30941Y-145859D01*
Y-147600D01*
Y-149341D01*
X31461Y-149126D01*
X31967Y-148620D01*
X32179Y-148108D01*
X32703D01*
X32915Y-148620D01*
X33421Y-149126D01*
X33941Y-149341D01*
Y-147600D01*
Y-145859D01*
D02*
G37*
G36*
X29941D02*
X29421Y-146074D01*
X28915Y-146580D01*
X28703Y-147092D01*
X28179D01*
X27967Y-146580D01*
X27461Y-146074D01*
X26941Y-145859D01*
Y-147600D01*
Y-149341D01*
X27461Y-149126D01*
X27967Y-148620D01*
X28179Y-148108D01*
X28703D01*
X28915Y-148620D01*
X29421Y-149126D01*
X29941Y-149341D01*
Y-147600D01*
Y-145859D01*
D02*
G37*
G36*
X25941D02*
X25421Y-146074D01*
X24915Y-146580D01*
X24703Y-147092D01*
X24179D01*
X23967Y-146580D01*
X23461Y-146074D01*
X22941Y-145859D01*
Y-147600D01*
Y-149341D01*
X23461Y-149126D01*
X23967Y-148620D01*
X24179Y-148108D01*
X24703D01*
X24915Y-148620D01*
X25421Y-149126D01*
X25941Y-149341D01*
Y-147600D01*
Y-145859D01*
D02*
G37*
G36*
X21941D02*
X21421Y-146074D01*
X20915Y-146580D01*
X20703Y-147092D01*
X20179D01*
X19967Y-146580D01*
X19461Y-146074D01*
X18941Y-145859D01*
Y-147600D01*
Y-149341D01*
X19461Y-149126D01*
X19967Y-148620D01*
X20179Y-148108D01*
X20703D01*
X20915Y-148620D01*
X21421Y-149126D01*
X21941Y-149341D01*
Y-147600D01*
Y-145859D01*
D02*
G37*
G36*
X17941D02*
X17421Y-146074D01*
X16915Y-146580D01*
X16703Y-147092D01*
X16179D01*
X15967Y-146580D01*
X15461Y-146074D01*
X14941Y-145859D01*
Y-147600D01*
Y-149341D01*
X15461Y-149126D01*
X15967Y-148620D01*
X16179Y-148108D01*
X16703D01*
X16915Y-148620D01*
X17421Y-149126D01*
X17941Y-149341D01*
Y-147600D01*
Y-145859D01*
D02*
G37*
G36*
X54941D02*
Y-147100D01*
X56182D01*
X55967Y-146580D01*
X55461Y-146074D01*
X54941Y-145859D01*
D02*
G37*
G36*
X53941D02*
X53421Y-146074D01*
X52915Y-146580D01*
X52700Y-147100D01*
X53941D01*
Y-145859D01*
D02*
G37*
G36*
X34941D02*
Y-147100D01*
X36182D01*
X35967Y-146580D01*
X35461Y-146074D01*
X34941Y-145859D01*
D02*
G37*
G36*
X13941D02*
X13421Y-146074D01*
X12915Y-146580D01*
X12700Y-147100D01*
X13941D01*
Y-145859D01*
D02*
G37*
G36*
X72350Y-145897D02*
Y-147138D01*
X73592D01*
X73376Y-146618D01*
X72870Y-146112D01*
X72350Y-145897D01*
D02*
G37*
G36*
X71350D02*
X70831Y-146112D01*
X70324Y-146618D01*
X70109Y-147138D01*
X71350D01*
Y-145897D01*
D02*
G37*
G36*
X56182Y-148100D02*
X54941D01*
Y-149341D01*
X55461Y-149126D01*
X55967Y-148620D01*
X56182Y-148100D01*
D02*
G37*
G36*
X53941D02*
X52700D01*
X52915Y-148620D01*
X53421Y-149126D01*
X53941Y-149341D01*
Y-148100D01*
D02*
G37*
G36*
X36182D02*
X34941D01*
Y-149341D01*
X35461Y-149126D01*
X35967Y-148620D01*
X36182Y-148100D01*
D02*
G37*
G36*
X13941D02*
X12700D01*
X12915Y-148620D01*
X13421Y-149126D01*
X13941Y-149341D01*
Y-148100D01*
D02*
G37*
G36*
X35941Y-149859D02*
X35421Y-150074D01*
X34915Y-150580D01*
X34703Y-151092D01*
X34179D01*
X33967Y-150580D01*
X33461Y-150074D01*
X32941Y-149859D01*
Y-151600D01*
Y-153341D01*
X33461Y-153126D01*
X33967Y-152620D01*
X34179Y-152108D01*
X34703D01*
X34915Y-152620D01*
X35421Y-153126D01*
X35941Y-153341D01*
Y-151600D01*
Y-149859D01*
D02*
G37*
G36*
X31941D02*
X31421Y-150074D01*
X30915Y-150580D01*
X30703Y-151092D01*
X30179D01*
X29967Y-150580D01*
X29461Y-150074D01*
X28941Y-149859D01*
Y-151600D01*
Y-153341D01*
X29461Y-153126D01*
X29967Y-152620D01*
X30179Y-152108D01*
X30703D01*
X30915Y-152620D01*
X31421Y-153126D01*
X31941Y-153341D01*
Y-151600D01*
Y-149859D01*
D02*
G37*
G36*
X27941D02*
X27421Y-150074D01*
X26915Y-150580D01*
X26703Y-151092D01*
X26179D01*
X25967Y-150580D01*
X25461Y-150074D01*
X24941Y-149859D01*
Y-151600D01*
Y-153341D01*
X25461Y-153126D01*
X25967Y-152620D01*
X26179Y-152108D01*
X26703D01*
X26915Y-152620D01*
X27421Y-153126D01*
X27941Y-153341D01*
Y-151600D01*
Y-149859D01*
D02*
G37*
G36*
X23941D02*
X23421Y-150074D01*
X22915Y-150580D01*
X22703Y-151092D01*
X22179D01*
X21967Y-150580D01*
X21461Y-150074D01*
X20941Y-149859D01*
Y-151600D01*
Y-153341D01*
X21461Y-153126D01*
X21967Y-152620D01*
X22179Y-152108D01*
X22703D01*
X22915Y-152620D01*
X23421Y-153126D01*
X23941Y-153341D01*
Y-151600D01*
Y-149859D01*
D02*
G37*
G36*
X19941D02*
X19421Y-150074D01*
X18915Y-150580D01*
X18703Y-151092D01*
X18179D01*
X17967Y-150580D01*
X17461Y-150074D01*
X16941Y-149859D01*
Y-151600D01*
Y-153341D01*
X17461Y-153126D01*
X17967Y-152620D01*
X18179Y-152108D01*
X18703D01*
X18915Y-152620D01*
X19421Y-153126D01*
X19941Y-153341D01*
Y-151600D01*
Y-149859D01*
D02*
G37*
G36*
X15941D02*
X15421Y-150074D01*
X14915Y-150580D01*
X14703Y-151092D01*
X14179D01*
X13967Y-150580D01*
X13461Y-150074D01*
X12941Y-149859D01*
Y-151600D01*
Y-153341D01*
X13461Y-153126D01*
X13967Y-152620D01*
X14179Y-152108D01*
X14703D01*
X14915Y-152620D01*
X15421Y-153126D01*
X15941Y-153341D01*
Y-151600D01*
Y-149859D01*
D02*
G37*
G36*
X55941D02*
X55421Y-150074D01*
X54915Y-150580D01*
X54703Y-151092D01*
X54179D01*
X53967Y-150580D01*
X53461Y-150074D01*
X52941Y-149859D01*
Y-151600D01*
Y-153341D01*
X53461Y-153126D01*
X53967Y-152620D01*
X54179Y-152108D01*
X54703D01*
X54915Y-152620D01*
X55421Y-153126D01*
X55941Y-153341D01*
Y-151600D01*
Y-149859D01*
D02*
G37*
G36*
X56941D02*
Y-151100D01*
X58182D01*
X57967Y-150580D01*
X57461Y-150074D01*
X56941Y-149859D01*
D02*
G37*
G36*
X51941D02*
X51421Y-150074D01*
X50915Y-150580D01*
X50700Y-151100D01*
X51941D01*
Y-149859D01*
D02*
G37*
G36*
X36941D02*
Y-151100D01*
X38182D01*
X37967Y-150580D01*
X37461Y-150074D01*
X36941Y-149859D01*
D02*
G37*
G36*
X11941D02*
X11421Y-150074D01*
X10915Y-150580D01*
X10700Y-151100D01*
X11941D01*
Y-149859D01*
D02*
G37*
G36*
X46033Y-148138D02*
X42550D01*
X42572Y-148191D01*
X42294Y-148606D01*
X38961D01*
Y-151173D01*
X44291D01*
X49622D01*
Y-148606D01*
X46288D01*
X46011Y-148191D01*
X46033Y-148138D01*
D02*
G37*
G36*
X6866Y-147832D02*
X2035D01*
Y-152663D01*
X2237D01*
X3593Y-152300D01*
X4809Y-151598D01*
X5801Y-150605D01*
X6503Y-149390D01*
X6866Y-148034D01*
Y-147832D01*
D02*
G37*
G36*
X1035D02*
X-3795D01*
Y-148034D01*
X-3432Y-149390D01*
X-2730Y-150605D01*
X-1738Y-151598D01*
X-522Y-152300D01*
X834Y-152663D01*
X1035D01*
Y-147832D01*
D02*
G37*
G36*
X-13134D02*
X-17965D01*
Y-152663D01*
X-17763D01*
X-16407Y-152300D01*
X-15191Y-151598D01*
X-14199Y-150605D01*
X-13497Y-149390D01*
X-13134Y-148034D01*
Y-147832D01*
D02*
G37*
G36*
X-18965D02*
X-23795D01*
Y-148034D01*
X-23432Y-149390D01*
X-22730Y-150605D01*
X-21738Y-151598D01*
X-20522Y-152300D01*
X-19166Y-152663D01*
X-18965D01*
Y-147832D01*
D02*
G37*
G36*
X58182Y-152100D02*
X56941D01*
Y-153341D01*
X57461Y-153126D01*
X57967Y-152620D01*
X58182Y-152100D01*
D02*
G37*
G36*
X51941D02*
X50700D01*
X50915Y-152620D01*
X51421Y-153126D01*
X51941Y-153341D01*
Y-152100D01*
D02*
G37*
G36*
X38182D02*
X36941D01*
Y-153341D01*
X37461Y-153126D01*
X37967Y-152620D01*
X38182Y-152100D01*
D02*
G37*
G36*
X11941D02*
X10700D01*
X10915Y-152620D01*
X11421Y-153126D01*
X11941Y-153341D01*
Y-152100D01*
D02*
G37*
G36*
X49622Y-152173D02*
X44791D01*
Y-154740D01*
X49622D01*
Y-152173D01*
D02*
G37*
G36*
X-25059Y-153859D02*
Y-155100D01*
X-23818D01*
X-24033Y-154580D01*
X-24539Y-154074D01*
X-25059Y-153859D01*
D02*
G37*
G36*
X83677Y-154905D02*
X81504D01*
Y-155996D01*
X83677D01*
Y-154905D01*
D02*
G37*
G36*
X43791Y-152173D02*
X38961D01*
Y-154712D01*
X35421D01*
Y-156109D01*
X-3728D01*
Y-152595D01*
X-13202D01*
Y-162069D01*
X-3728D01*
Y-158556D01*
X35421D01*
Y-160249D01*
X37064D01*
Y-171838D01*
X35421D01*
Y-178950D01*
X40957D01*
Y-171838D01*
X39511D01*
Y-166354D01*
X42294D01*
X42572Y-166770D01*
X42550Y-166823D01*
X46033D01*
X46011Y-166770D01*
X46288Y-166354D01*
X49622D01*
Y-163787D01*
X44291D01*
Y-163287D01*
X43791D01*
Y-160221D01*
X41154D01*
Y-158704D01*
X52153D01*
Y-160052D01*
X56509D01*
Y-154909D01*
X52153D01*
Y-156257D01*
X41154D01*
Y-154740D01*
X43791D01*
Y-152173D01*
D02*
G37*
G36*
X-23818Y-156100D02*
X-25059D01*
Y-157341D01*
X-24539Y-157126D01*
X-24033Y-156620D01*
X-23818Y-156100D01*
D02*
G37*
G36*
X-23059Y-157859D02*
Y-159100D01*
X-21818D01*
X-22033Y-158580D01*
X-22539Y-158074D01*
X-23059Y-157859D01*
D02*
G37*
G36*
X-24059D02*
X-24579Y-158074D01*
X-25085Y-158580D01*
X-25300Y-159100D01*
X-24059D01*
Y-157859D01*
D02*
G37*
G36*
X-21818Y-160100D02*
X-23059D01*
Y-161341D01*
X-22539Y-161126D01*
X-22033Y-160620D01*
X-21818Y-160100D01*
D02*
G37*
G36*
X-24059D02*
X-25300D01*
X-25085Y-160620D01*
X-24579Y-161126D01*
X-24059Y-161341D01*
Y-160100D01*
D02*
G37*
G36*
X49622Y-160221D02*
X44791D01*
Y-162787D01*
X49622D01*
Y-160221D01*
D02*
G37*
G36*
X33941Y-161859D02*
X33421Y-162074D01*
X32915Y-162580D01*
X32703Y-163092D01*
X32179D01*
X31967Y-162580D01*
X31461Y-162074D01*
X30941Y-161859D01*
Y-163600D01*
Y-165341D01*
X31461Y-165126D01*
X31967Y-164620D01*
X32179Y-164108D01*
X32703D01*
X32915Y-164620D01*
X33421Y-165126D01*
X33941Y-165341D01*
Y-163600D01*
Y-161859D01*
D02*
G37*
G36*
X29941D02*
X29421Y-162074D01*
X28915Y-162580D01*
X28703Y-163092D01*
X28179D01*
X27967Y-162580D01*
X27461Y-162074D01*
X26941Y-161859D01*
Y-163600D01*
Y-165341D01*
X27461Y-165126D01*
X27967Y-164620D01*
X28179Y-164108D01*
X28703D01*
X28915Y-164620D01*
X29421Y-165126D01*
X29941Y-165341D01*
Y-163600D01*
Y-161859D01*
D02*
G37*
G36*
X25941D02*
X25421Y-162074D01*
X24915Y-162580D01*
X24703Y-163092D01*
X24179D01*
X23967Y-162580D01*
X23461Y-162074D01*
X22941Y-161859D01*
Y-163600D01*
Y-165341D01*
X23461Y-165126D01*
X23967Y-164620D01*
X24179Y-164108D01*
X24703D01*
X24915Y-164620D01*
X25421Y-165126D01*
X25941Y-165341D01*
Y-163600D01*
Y-161859D01*
D02*
G37*
G36*
X21941D02*
X21421Y-162074D01*
X20915Y-162580D01*
X20703Y-163092D01*
X20179D01*
X19967Y-162580D01*
X19461Y-162074D01*
X18941Y-161859D01*
Y-163600D01*
Y-165341D01*
X19461Y-165126D01*
X19967Y-164620D01*
X20179Y-164108D01*
X20703D01*
X20915Y-164620D01*
X21421Y-165126D01*
X21941Y-165341D01*
Y-163600D01*
Y-161859D01*
D02*
G37*
G36*
X17941D02*
X17421Y-162074D01*
X16915Y-162580D01*
X16703Y-163092D01*
X16179D01*
X15967Y-162580D01*
X15461Y-162074D01*
X14941Y-161859D01*
Y-163600D01*
Y-165341D01*
X15461Y-165126D01*
X15967Y-164620D01*
X16179Y-164108D01*
X16703D01*
X16915Y-164620D01*
X17421Y-165126D01*
X17941Y-165341D01*
Y-163600D01*
Y-161859D01*
D02*
G37*
G36*
X13941D02*
X13421Y-162074D01*
X12915Y-162580D01*
X12703Y-163092D01*
X12179D01*
X11967Y-162580D01*
X11461Y-162074D01*
X10941Y-161859D01*
Y-163600D01*
Y-165341D01*
X11461Y-165126D01*
X11967Y-164620D01*
X12179Y-164108D01*
X12703D01*
X12915Y-164620D01*
X13421Y-165126D01*
X13941Y-165341D01*
Y-163600D01*
Y-161859D01*
D02*
G37*
G36*
X34941D02*
Y-163100D01*
X36182D01*
X35967Y-162580D01*
X35461Y-162074D01*
X34941Y-161859D01*
D02*
G37*
G36*
X9941D02*
X9421Y-162074D01*
X8915Y-162580D01*
X8700Y-163100D01*
X9941D01*
Y-161859D01*
D02*
G37*
G36*
X36182Y-164100D02*
X34941D01*
Y-165341D01*
X35461Y-165126D01*
X35967Y-164620D01*
X36182Y-164100D01*
D02*
G37*
G36*
X9941D02*
X8700D01*
X8915Y-164620D01*
X9421Y-165126D01*
X9941Y-165341D01*
Y-164100D01*
D02*
G37*
G36*
X2237Y-162002D02*
X2035D01*
Y-166832D01*
X6866D01*
Y-166630D01*
X6503Y-165275D01*
X5801Y-164059D01*
X4809Y-163067D01*
X3593Y-162365D01*
X2237Y-162002D01*
D02*
G37*
G36*
X-17763D02*
X-17965D01*
Y-166832D01*
X-13134D01*
Y-166630D01*
X-13497Y-165275D01*
X-14199Y-164059D01*
X-15191Y-163067D01*
X-16407Y-162365D01*
X-17763Y-162002D01*
D02*
G37*
G36*
X1035D02*
X834D01*
X-522Y-162365D01*
X-1738Y-163067D01*
X-2730Y-164059D01*
X-3432Y-165275D01*
X-3795Y-166630D01*
Y-166832D01*
X1035D01*
Y-162002D01*
D02*
G37*
G36*
X-18965D02*
X-19166D01*
X-20522Y-162365D01*
X-21738Y-163067D01*
X-22730Y-164059D01*
X-23432Y-165275D01*
X-23795Y-166630D01*
Y-166832D01*
X-18965D01*
Y-162002D01*
D02*
G37*
G36*
X27941Y-165859D02*
X27421Y-166074D01*
X26915Y-166580D01*
X26703Y-167092D01*
X26179D01*
X25967Y-166580D01*
X25461Y-166074D01*
X24941Y-165859D01*
Y-167600D01*
Y-169341D01*
X25461Y-169126D01*
X25967Y-168620D01*
X26179Y-168108D01*
X26703D01*
X26915Y-168620D01*
X27421Y-169126D01*
X27941Y-169341D01*
Y-167600D01*
Y-165859D01*
D02*
G37*
G36*
X23941D02*
X23421Y-166074D01*
X22915Y-166580D01*
X22703Y-167092D01*
X22179D01*
X21967Y-166580D01*
X21461Y-166074D01*
X20941Y-165859D01*
Y-167600D01*
Y-169341D01*
X21461Y-169126D01*
X21967Y-168620D01*
X22179Y-168108D01*
X22703D01*
X22915Y-168620D01*
X23421Y-169126D01*
X23941Y-169341D01*
Y-167600D01*
Y-165859D01*
D02*
G37*
G36*
X19941D02*
X19421Y-166074D01*
X18915Y-166580D01*
X18703Y-167092D01*
X18179D01*
X17967Y-166580D01*
X17461Y-166074D01*
X16941Y-165859D01*
Y-167600D01*
Y-169341D01*
X17461Y-169126D01*
X17967Y-168620D01*
X18179Y-168108D01*
X18703D01*
X18915Y-168620D01*
X19421Y-169126D01*
X19941Y-169341D01*
Y-167600D01*
Y-165859D01*
D02*
G37*
G36*
X15941D02*
X15421Y-166074D01*
X14915Y-166580D01*
X14703Y-167092D01*
X14179D01*
X13967Y-166580D01*
X13461Y-166074D01*
X12941Y-165859D01*
Y-167600D01*
Y-169341D01*
X13461Y-169126D01*
X13967Y-168620D01*
X14179Y-168108D01*
X14703D01*
X14915Y-168620D01*
X15421Y-169126D01*
X15941Y-169341D01*
Y-167600D01*
Y-165859D01*
D02*
G37*
G36*
X28941D02*
Y-167100D01*
X30182D01*
X29967Y-166580D01*
X29461Y-166074D01*
X28941Y-165859D01*
D02*
G37*
G36*
X11941D02*
X11421Y-166074D01*
X10915Y-166580D01*
X10700Y-167100D01*
X11941D01*
Y-165859D01*
D02*
G37*
G36*
X-7059D02*
Y-167100D01*
X-5818D01*
X-6033Y-166580D01*
X-6539Y-166074D01*
X-7059Y-165859D01*
D02*
G37*
G36*
X-8059D02*
X-8579Y-166074D01*
X-9085Y-166580D01*
X-9300Y-167100D01*
X-8059D01*
Y-165859D01*
D02*
G37*
G36*
X46033Y-167823D02*
X44791D01*
Y-169064D01*
X45311Y-168849D01*
X45817Y-168342D01*
X46033Y-167823D01*
D02*
G37*
G36*
X43791D02*
X42550D01*
X42765Y-168342D01*
X43272Y-168849D01*
X43791Y-169064D01*
Y-167823D01*
D02*
G37*
G36*
X11941Y-168100D02*
X10700D01*
X10915Y-168620D01*
X11421Y-169126D01*
X11941Y-169341D01*
Y-168100D01*
D02*
G37*
G36*
X-5818D02*
X-7059D01*
Y-169341D01*
X-6539Y-169126D01*
X-6033Y-168620D01*
X-5818Y-168100D01*
D02*
G37*
G36*
X-8059D02*
X-9300D01*
X-9085Y-168620D01*
X-8579Y-169126D01*
X-8059Y-169341D01*
Y-168100D01*
D02*
G37*
G36*
X21941Y-169859D02*
X21421Y-170074D01*
X20915Y-170580D01*
X20703Y-171092D01*
X20179D01*
X19967Y-170580D01*
X19461Y-170074D01*
X18941Y-169859D01*
Y-171600D01*
Y-173341D01*
X19461Y-173126D01*
X19967Y-172620D01*
X20179Y-172108D01*
X20703D01*
X20915Y-172620D01*
X21421Y-173126D01*
X21941Y-173341D01*
Y-171600D01*
Y-169859D01*
D02*
G37*
G36*
X17941D02*
X17421Y-170074D01*
X16915Y-170580D01*
X16703Y-171092D01*
X16179D01*
X15967Y-170580D01*
X15461Y-170074D01*
X14941Y-169859D01*
Y-171600D01*
Y-173341D01*
X15461Y-173126D01*
X15967Y-172620D01*
X16179Y-172108D01*
X16703D01*
X16915Y-172620D01*
X17421Y-173126D01*
X17941Y-173341D01*
Y-171600D01*
Y-169859D01*
D02*
G37*
G36*
X13941D02*
X13421Y-170074D01*
X12915Y-170580D01*
X12703Y-171092D01*
X12179D01*
X11967Y-170580D01*
X11461Y-170074D01*
X10941Y-169859D01*
Y-171600D01*
Y-173341D01*
X11461Y-173126D01*
X11967Y-172620D01*
X12179Y-172108D01*
X12703D01*
X12915Y-172620D01*
X13421Y-173126D01*
X13941Y-173341D01*
Y-171600D01*
Y-169859D01*
D02*
G37*
G36*
X22941D02*
Y-171100D01*
X24182D01*
X23967Y-170580D01*
X23461Y-170074D01*
X22941Y-169859D01*
D02*
G37*
G36*
X9941D02*
X9421Y-170074D01*
X8915Y-170580D01*
X8700Y-171100D01*
X9941D01*
Y-169859D01*
D02*
G37*
G36*
X-9059D02*
Y-171100D01*
X-7818D01*
X-8033Y-170580D01*
X-8539Y-170074D01*
X-9059Y-169859D01*
D02*
G37*
G36*
X-10059D02*
X-10579Y-170074D01*
X-11085Y-170580D01*
X-11300Y-171100D01*
X-10059D01*
Y-169859D01*
D02*
G37*
G36*
X6866Y-167832D02*
X2035D01*
Y-172663D01*
X2237D01*
X3593Y-172300D01*
X4809Y-171598D01*
X5801Y-170605D01*
X6503Y-169390D01*
X6866Y-168034D01*
Y-167832D01*
D02*
G37*
G36*
X1035D02*
X-3795D01*
Y-168034D01*
X-3432Y-169390D01*
X-2730Y-170605D01*
X-1738Y-171598D01*
X-522Y-172300D01*
X834Y-172663D01*
X1035D01*
Y-167832D01*
D02*
G37*
G36*
X-13134D02*
X-17965D01*
Y-172663D01*
X-17763D01*
X-16407Y-172300D01*
X-15191Y-171598D01*
X-14199Y-170605D01*
X-13497Y-169390D01*
X-13134Y-168034D01*
Y-167832D01*
D02*
G37*
G36*
X-18965D02*
X-23795D01*
Y-168034D01*
X-23432Y-169390D01*
X-22730Y-170605D01*
X-21738Y-171598D01*
X-20522Y-172300D01*
X-19166Y-172663D01*
X-18965D01*
Y-167832D01*
D02*
G37*
G36*
X24182Y-172100D02*
X22941D01*
Y-173341D01*
X23461Y-173126D01*
X23967Y-172620D01*
X24182Y-172100D01*
D02*
G37*
G36*
X9941D02*
X8700D01*
X8915Y-172620D01*
X9421Y-173126D01*
X9941Y-173341D01*
Y-172100D01*
D02*
G37*
G36*
X-7818D02*
X-9059D01*
Y-173341D01*
X-8539Y-173126D01*
X-8033Y-172620D01*
X-7818Y-172100D01*
D02*
G37*
G36*
X-10059D02*
X-11300D01*
X-11085Y-172620D01*
X-10579Y-173126D01*
X-10059Y-173341D01*
Y-172100D01*
D02*
G37*
G36*
X-15834Y-174791D02*
X-20977D01*
Y-175789D01*
X-22764D01*
X-23304Y-175565D01*
X-23940D01*
X-24528Y-175809D01*
X-24979Y-176259D01*
X-25222Y-176847D01*
Y-177484D01*
X-24979Y-178072D01*
X-24528Y-178522D01*
X-23940Y-178765D01*
X-23304D01*
X-22716Y-178522D01*
X-22430Y-178236D01*
X-21946D01*
X-21568Y-178531D01*
Y-179726D01*
X-22764D01*
X-23304Y-179502D01*
X-23940D01*
X-24528Y-179746D01*
X-24979Y-180196D01*
X-25222Y-180784D01*
Y-181421D01*
X-24979Y-182009D01*
X-24735Y-182252D01*
X-24584Y-182579D01*
X-24735Y-182905D01*
X-24979Y-183149D01*
X-25222Y-183737D01*
Y-184373D01*
X-24979Y-184961D01*
X-24528Y-185412D01*
X-23940Y-185655D01*
X-23304D01*
X-22716Y-185412D01*
X-22583Y-185279D01*
X-21568D01*
Y-186036D01*
X-20977D01*
Y-186568D01*
X-22879D01*
X-23304Y-186392D01*
X-23940D01*
X-24528Y-186636D01*
X-24979Y-187086D01*
X-25222Y-187674D01*
Y-188310D01*
X-24979Y-188899D01*
X-24528Y-189349D01*
X-24331Y-189430D01*
X-24331Y-189971D01*
X-24579Y-190074D01*
X-25085Y-190580D01*
X-25300Y-191100D01*
X-21818D01*
X-22033Y-190580D01*
X-22539Y-190074D01*
X-22850Y-189945D01*
Y-189404D01*
X-22716Y-189349D01*
X-22586Y-189219D01*
X-20977D01*
Y-189776D01*
X-16988D01*
X-16781Y-190276D01*
X-17085Y-190580D01*
X-17300Y-191100D01*
X-15559D01*
Y-191600D01*
X-15059D01*
Y-193341D01*
X-14539Y-193126D01*
X-14033Y-192620D01*
X-13821Y-192108D01*
X-13297D01*
X-13085Y-192620D01*
X-12579Y-193126D01*
X-12059Y-193341D01*
Y-191600D01*
Y-189859D01*
X-12579Y-190074D01*
X-13085Y-190580D01*
X-13297Y-191092D01*
X-13821D01*
X-14033Y-190580D01*
X-14539Y-190074D01*
X-15201Y-189800D01*
X-15344D01*
X-15834Y-189776D01*
X-15834Y-185814D01*
X-17802D01*
Y-182493D01*
Y-178753D01*
X-15834D01*
Y-174791D01*
D02*
G37*
G36*
X30182Y-168100D02*
X28941D01*
Y-169831D01*
X28951Y-169862D01*
X28912Y-169957D01*
Y-170594D01*
X29155Y-171182D01*
X29311Y-171338D01*
X29210Y-171838D01*
X27940D01*
Y-178950D01*
X33477D01*
Y-171838D01*
X32034D01*
Y-170781D01*
X32112Y-170594D01*
Y-169957D01*
X31868Y-169369D01*
X31418Y-168919D01*
X30830Y-168676D01*
X30485D01*
X30142Y-168197D01*
X30182Y-168100D01*
D02*
G37*
G36*
X70315Y-179821D02*
X69073D01*
Y-181062D01*
X69593Y-180847D01*
X70099Y-180340D01*
X70315Y-179821D01*
D02*
G37*
G36*
X68073D02*
X66832D01*
X67048Y-180340D01*
X67554Y-180847D01*
X68073Y-181062D01*
Y-179821D01*
D02*
G37*
G36*
X30996Y-180299D02*
X27740D01*
Y-183555D01*
X30996D01*
Y-180299D01*
D02*
G37*
G36*
X23941Y-189859D02*
X23421Y-190074D01*
X22915Y-190580D01*
X22703Y-191092D01*
X22179D01*
X21967Y-190580D01*
X21461Y-190074D01*
X20941Y-189859D01*
Y-191600D01*
Y-193341D01*
X21461Y-193126D01*
X21967Y-192620D01*
X22179Y-192108D01*
X22703D01*
X22915Y-192620D01*
X23421Y-193126D01*
X23941Y-193341D01*
Y-191600D01*
Y-189859D01*
D02*
G37*
G36*
X19941D02*
X19421Y-190074D01*
X18915Y-190580D01*
X18703Y-191092D01*
X18179D01*
X17967Y-190580D01*
X17461Y-190074D01*
X16941Y-189859D01*
Y-191600D01*
Y-193341D01*
X17461Y-193126D01*
X17967Y-192620D01*
X18179Y-192108D01*
X18703D01*
X18915Y-192620D01*
X19421Y-193126D01*
X19941Y-193341D01*
Y-191600D01*
Y-189859D01*
D02*
G37*
G36*
X15941D02*
X15421Y-190074D01*
X14915Y-190580D01*
X14703Y-191092D01*
X14179D01*
X13967Y-190580D01*
X13461Y-190074D01*
X12941Y-189859D01*
Y-191600D01*
Y-193341D01*
X13461Y-193126D01*
X13967Y-192620D01*
X14179Y-192108D01*
X14703D01*
X14915Y-192620D01*
X15421Y-193126D01*
X15941Y-193341D01*
Y-191600D01*
Y-189859D01*
D02*
G37*
G36*
X11941D02*
X11421Y-190074D01*
X10915Y-190580D01*
X10703Y-191092D01*
X10179D01*
X9967Y-190580D01*
X9461Y-190074D01*
X8941Y-189859D01*
Y-191600D01*
Y-193341D01*
X9461Y-193126D01*
X9967Y-192620D01*
X10179Y-192108D01*
X10703D01*
X10915Y-192620D01*
X11421Y-193126D01*
X11941Y-193341D01*
Y-191600D01*
Y-189859D01*
D02*
G37*
G36*
X7941D02*
X7421Y-190074D01*
X6915Y-190580D01*
X6703Y-191092D01*
X6179D01*
X5967Y-190580D01*
X5461Y-190074D01*
X4941Y-189859D01*
Y-191600D01*
Y-193341D01*
X5461Y-193126D01*
X5967Y-192620D01*
X6179Y-192108D01*
X6703D01*
X6915Y-192620D01*
X7421Y-193126D01*
X7941Y-193341D01*
Y-191600D01*
Y-189859D01*
D02*
G37*
G36*
X-4059D02*
X-4579Y-190074D01*
X-5085Y-190580D01*
X-5297Y-191092D01*
X-5821D01*
X-6033Y-190580D01*
X-6539Y-190074D01*
X-7059Y-189859D01*
Y-191600D01*
Y-193341D01*
X-6539Y-193126D01*
X-6033Y-192620D01*
X-5821Y-192108D01*
X-5297D01*
X-5085Y-192620D01*
X-4579Y-193126D01*
X-4059Y-193341D01*
Y-191600D01*
Y-189859D01*
D02*
G37*
G36*
X-8059D02*
X-8579Y-190074D01*
X-9085Y-190580D01*
X-9297Y-191092D01*
X-9821D01*
X-10033Y-190580D01*
X-10539Y-190074D01*
X-11059Y-189859D01*
Y-191600D01*
Y-193341D01*
X-10539Y-193126D01*
X-10033Y-192620D01*
X-9821Y-192108D01*
X-9297D01*
X-9085Y-192620D01*
X-8579Y-193126D01*
X-8059Y-193341D01*
Y-191600D01*
Y-189859D01*
D02*
G37*
G36*
X55941D02*
X55421Y-190074D01*
X54915Y-190580D01*
X54703Y-191092D01*
X54179D01*
X53967Y-190580D01*
X53461Y-190074D01*
X52941Y-189859D01*
Y-191600D01*
Y-193341D01*
X53461Y-193126D01*
X53967Y-192620D01*
X54179Y-192108D01*
X54703D01*
X54915Y-192620D01*
X55421Y-193126D01*
X55941Y-193341D01*
Y-191600D01*
Y-189859D01*
D02*
G37*
G36*
X56941D02*
Y-191100D01*
X58182D01*
X57967Y-190580D01*
X57461Y-190074D01*
X56941Y-189859D01*
D02*
G37*
G36*
X51941D02*
X51421Y-190074D01*
X50915Y-190580D01*
X50700Y-191100D01*
X51941D01*
Y-189859D01*
D02*
G37*
G36*
X24941D02*
Y-191100D01*
X26182D01*
X25967Y-190580D01*
X25461Y-190074D01*
X24941Y-189859D01*
D02*
G37*
G36*
X3941D02*
X3421Y-190074D01*
X2915Y-190580D01*
X2700Y-191100D01*
X3941D01*
Y-189859D01*
D02*
G37*
G36*
X-3059D02*
Y-191100D01*
X-1818D01*
X-2033Y-190580D01*
X-2539Y-190074D01*
X-3059Y-189859D01*
D02*
G37*
G36*
X33237Y-190461D02*
X31996D01*
Y-191702D01*
X32516Y-191487D01*
X33022Y-190980D01*
X33237Y-190461D01*
D02*
G37*
G36*
X30996D02*
X29755D01*
X29970Y-190980D01*
X30476Y-191487D01*
X30996Y-191702D01*
Y-190461D01*
D02*
G37*
G36*
X58182Y-192100D02*
X56941D01*
Y-193341D01*
X57461Y-193126D01*
X57967Y-192620D01*
X58182Y-192100D01*
D02*
G37*
G36*
X51941D02*
X50700D01*
X50915Y-192620D01*
X51421Y-193126D01*
X51941Y-193341D01*
Y-192100D01*
D02*
G37*
G36*
X26182D02*
X24941D01*
Y-193341D01*
X25461Y-193126D01*
X25967Y-192620D01*
X26182Y-192100D01*
D02*
G37*
G36*
X3941D02*
X2700D01*
X2915Y-192620D01*
X3421Y-193126D01*
X3941Y-193341D01*
Y-192100D01*
D02*
G37*
G36*
X-1818D02*
X-3059D01*
Y-193341D01*
X-2539Y-193126D01*
X-2033Y-192620D01*
X-1818Y-192100D01*
D02*
G37*
G36*
X-16059D02*
X-17300D01*
X-17085Y-192620D01*
X-16579Y-193126D01*
X-16059Y-193341D01*
Y-192100D01*
D02*
G37*
G36*
X-21818D02*
X-23059D01*
Y-193341D01*
X-22539Y-193126D01*
X-22033Y-192620D01*
X-21818Y-192100D01*
D02*
G37*
G36*
X-24059D02*
X-25300D01*
X-25085Y-192620D01*
X-24579Y-193126D01*
X-24059Y-193341D01*
Y-192100D01*
D02*
G37*
G36*
X25941Y-193859D02*
X25421Y-194074D01*
X24915Y-194580D01*
X24703Y-195092D01*
X24179D01*
X23967Y-194580D01*
X23461Y-194074D01*
X22941Y-193859D01*
Y-195600D01*
Y-197341D01*
X23461Y-197126D01*
X23967Y-196620D01*
X24179Y-196108D01*
X24703D01*
X24915Y-196620D01*
X25421Y-197126D01*
X25941Y-197341D01*
Y-195600D01*
Y-193859D01*
D02*
G37*
G36*
X21941D02*
X21421Y-194074D01*
X20915Y-194580D01*
X20703Y-195092D01*
X20179D01*
X19967Y-194580D01*
X19461Y-194074D01*
X18941Y-193859D01*
Y-195600D01*
Y-197341D01*
X19461Y-197126D01*
X19967Y-196620D01*
X20179Y-196108D01*
X20703D01*
X20915Y-196620D01*
X21421Y-197126D01*
X21941Y-197341D01*
Y-195600D01*
Y-193859D01*
D02*
G37*
G36*
X17941D02*
X17421Y-194074D01*
X16915Y-194580D01*
X16703Y-195092D01*
X16179D01*
X15967Y-194580D01*
X15461Y-194074D01*
X14941Y-193859D01*
Y-195600D01*
Y-197341D01*
X15461Y-197126D01*
X15967Y-196620D01*
X16179Y-196108D01*
X16703D01*
X16915Y-196620D01*
X17421Y-197126D01*
X17941Y-197341D01*
Y-195600D01*
Y-193859D01*
D02*
G37*
G36*
X13941D02*
X13421Y-194074D01*
X12915Y-194580D01*
X12703Y-195092D01*
X12179D01*
X11967Y-194580D01*
X11461Y-194074D01*
X10941Y-193859D01*
Y-195600D01*
Y-197341D01*
X11461Y-197126D01*
X11967Y-196620D01*
X12179Y-196108D01*
X12703D01*
X12915Y-196620D01*
X13421Y-197126D01*
X13941Y-197341D01*
Y-195600D01*
Y-193859D01*
D02*
G37*
G36*
X53941D02*
X53421Y-194074D01*
X52915Y-194580D01*
X52703Y-195092D01*
X52179D01*
X51967Y-194580D01*
X51461Y-194074D01*
X50941Y-193859D01*
Y-195600D01*
Y-197341D01*
X51461Y-197126D01*
X51967Y-196620D01*
X52179Y-196108D01*
X52703D01*
X52915Y-196620D01*
X53421Y-197126D01*
X53941Y-197341D01*
Y-195600D01*
Y-193859D01*
D02*
G37*
G36*
X54941D02*
Y-195100D01*
X56182D01*
X55967Y-194580D01*
X55461Y-194074D01*
X54941Y-193859D01*
D02*
G37*
G36*
X49941D02*
X49421Y-194074D01*
X48915Y-194580D01*
X48700Y-195100D01*
X49941D01*
Y-193859D01*
D02*
G37*
G36*
X26941D02*
Y-195100D01*
X28182D01*
X27967Y-194580D01*
X27461Y-194074D01*
X26941Y-193859D01*
D02*
G37*
G36*
X9941D02*
X9421Y-194074D01*
X8915Y-194580D01*
X8700Y-195100D01*
X9941D01*
Y-193859D01*
D02*
G37*
G36*
X-9059D02*
Y-195100D01*
X-7818D01*
X-8033Y-194580D01*
X-8539Y-194074D01*
X-9059Y-193859D01*
D02*
G37*
G36*
X-10059D02*
X-10579Y-194074D01*
X-11085Y-194580D01*
X-11300Y-195100D01*
X-10059D01*
Y-193859D01*
D02*
G37*
G36*
X56182Y-196100D02*
X54941D01*
Y-197341D01*
X55461Y-197126D01*
X55967Y-196620D01*
X56182Y-196100D01*
D02*
G37*
G36*
X49941D02*
X48700D01*
X48915Y-196620D01*
X49421Y-197126D01*
X49941Y-197341D01*
Y-196100D01*
D02*
G37*
G36*
X28182D02*
X26941D01*
Y-197341D01*
X27461Y-197126D01*
X27967Y-196620D01*
X28182Y-196100D01*
D02*
G37*
G36*
X9941D02*
X8700D01*
X8915Y-196620D01*
X9421Y-197126D01*
X9941Y-197341D01*
Y-196100D01*
D02*
G37*
G36*
X-7818D02*
X-9059D01*
Y-197341D01*
X-8539Y-197126D01*
X-8033Y-196620D01*
X-7818Y-196100D01*
D02*
G37*
G36*
X-10059D02*
X-11300D01*
X-11085Y-196620D01*
X-10579Y-197126D01*
X-10059Y-197341D01*
Y-196100D01*
D02*
G37*
G36*
X19941Y-197859D02*
X19421Y-198074D01*
X18915Y-198580D01*
X18703Y-199092D01*
X18179D01*
X17967Y-198580D01*
X17461Y-198074D01*
X16941Y-197859D01*
Y-199600D01*
Y-201341D01*
X17461Y-201126D01*
X17967Y-200620D01*
X18179Y-200108D01*
X18703D01*
X18915Y-200620D01*
X19421Y-201126D01*
X19941Y-201341D01*
Y-199600D01*
Y-197859D01*
D02*
G37*
G36*
X15941D02*
X15421Y-198074D01*
X14915Y-198580D01*
X14703Y-199092D01*
X14179D01*
X13967Y-198580D01*
X13461Y-198074D01*
X12941Y-197859D01*
Y-199600D01*
Y-201341D01*
X13461Y-201126D01*
X13967Y-200620D01*
X14179Y-200108D01*
X14703D01*
X14915Y-200620D01*
X15421Y-201126D01*
X15941Y-201341D01*
Y-199600D01*
Y-197859D01*
D02*
G37*
G36*
X55941D02*
X55421Y-198074D01*
X54915Y-198580D01*
X54703Y-199092D01*
X54179D01*
X53967Y-198580D01*
X53461Y-198074D01*
X52941Y-197859D01*
Y-199600D01*
Y-201341D01*
X53461Y-201126D01*
X53967Y-200620D01*
X54179Y-200108D01*
X54703D01*
X54915Y-200620D01*
X55421Y-201126D01*
X55941Y-201341D01*
Y-199600D01*
Y-197859D01*
D02*
G37*
G36*
X56941D02*
Y-199100D01*
X58182D01*
X57967Y-198580D01*
X57461Y-198074D01*
X56941Y-197859D01*
D02*
G37*
G36*
X47941D02*
X47421Y-198074D01*
X46915Y-198580D01*
X46700Y-199100D01*
X47941D01*
Y-197859D01*
D02*
G37*
G36*
X20941D02*
Y-199100D01*
X22182D01*
X21967Y-198580D01*
X21461Y-198074D01*
X20941Y-197859D01*
D02*
G37*
G36*
X11941D02*
X11421Y-198074D01*
X10915Y-198580D01*
X10700Y-199100D01*
X11941D01*
Y-197859D01*
D02*
G37*
G36*
X-7059D02*
Y-199100D01*
X-5818D01*
X-6033Y-198580D01*
X-6539Y-198074D01*
X-7059Y-197859D01*
D02*
G37*
G36*
X-8059D02*
X-8579Y-198074D01*
X-9085Y-198580D01*
X-9300Y-199100D01*
X-8059D01*
Y-197859D01*
D02*
G37*
G36*
X-17763Y-195150D02*
X-17965D01*
Y-199980D01*
X-13134D01*
Y-199778D01*
X-13497Y-198423D01*
X-14199Y-197207D01*
X-15191Y-196215D01*
X-16407Y-195513D01*
X-17763Y-195150D01*
D02*
G37*
G36*
X2237D02*
X2035D01*
Y-199980D01*
X6866D01*
Y-199778D01*
X6503Y-198423D01*
X5801Y-197207D01*
X4809Y-196215D01*
X3593Y-195513D01*
X2237Y-195150D01*
D02*
G37*
G36*
X-18965D02*
X-19166D01*
X-20522Y-195513D01*
X-21738Y-196215D01*
X-22730Y-197207D01*
X-23432Y-198423D01*
X-23795Y-199778D01*
Y-199980D01*
X-18965D01*
Y-195150D01*
D02*
G37*
G36*
X1035D02*
X834D01*
X-522Y-195513D01*
X-1738Y-196215D01*
X-2730Y-197207D01*
X-3432Y-198423D01*
X-3795Y-199778D01*
Y-199980D01*
X1035D01*
Y-195150D01*
D02*
G37*
G36*
X44791Y-199046D02*
Y-200287D01*
X46033D01*
X45817Y-199768D01*
X45311Y-199261D01*
X44791Y-199046D01*
D02*
G37*
G36*
X43791D02*
X43272Y-199261D01*
X42765Y-199768D01*
X42550Y-200287D01*
X43791D01*
Y-199046D01*
D02*
G37*
G36*
X58182Y-200100D02*
X56941D01*
Y-201341D01*
X57461Y-201126D01*
X57967Y-200620D01*
X58182Y-200100D01*
D02*
G37*
G36*
X35252Y-180299D02*
X35003Y-180299D01*
X31996D01*
Y-184055D01*
X31496D01*
Y-184555D01*
X27740D01*
Y-187811D01*
X30273D01*
Y-188639D01*
X29970Y-188941D01*
X29755Y-189461D01*
X33237D01*
X33022Y-188941D01*
X32720Y-188639D01*
Y-187811D01*
X35252Y-187811D01*
X35669Y-187611D01*
X36966D01*
Y-207861D01*
X35421D01*
Y-209257D01*
X-3728D01*
Y-205743D01*
X-13202D01*
Y-215217D01*
X-3728D01*
Y-211704D01*
X35421D01*
Y-213398D01*
X35746D01*
X35845Y-213898D01*
X35421Y-214074D01*
X34915Y-214580D01*
X34700Y-215100D01*
X38182D01*
X37967Y-214580D01*
X37461Y-214074D01*
X37037Y-213898D01*
X37136Y-213398D01*
X38961D01*
Y-215937D01*
X43791D01*
Y-213370D01*
X41154D01*
Y-211853D01*
X53137D01*
Y-213202D01*
X57493D01*
Y-208058D01*
X53137D01*
Y-209406D01*
X41154D01*
Y-207890D01*
X43791D01*
Y-204823D01*
X44291D01*
Y-204323D01*
X49622D01*
Y-201756D01*
X49246D01*
X49147Y-201256D01*
X49461Y-201126D01*
X49967Y-200620D01*
X50179Y-200108D01*
X50703D01*
X50915Y-200620D01*
X51421Y-201126D01*
X51941Y-201341D01*
Y-199600D01*
Y-197859D01*
X51421Y-198074D01*
X50915Y-198580D01*
X50703Y-199092D01*
X50179D01*
X49967Y-198580D01*
X49461Y-198074D01*
X48941Y-197859D01*
Y-199600D01*
X48441D01*
Y-200100D01*
X46700D01*
X46915Y-200620D01*
X47421Y-201126D01*
X47735Y-201256D01*
X47636Y-201756D01*
X46288D01*
X46011Y-201340D01*
X46033Y-201287D01*
X42550D01*
X42572Y-201340D01*
X42294Y-201756D01*
X39413D01*
Y-187611D01*
X40957D01*
Y-180499D01*
X35669D01*
X35252Y-180299D01*
D02*
G37*
G36*
X22182Y-200100D02*
X20941D01*
Y-201341D01*
X21461Y-201126D01*
X21967Y-200620D01*
X22182Y-200100D01*
D02*
G37*
G36*
X11941D02*
X10700D01*
X10915Y-200620D01*
X11421Y-201126D01*
X11941Y-201341D01*
Y-200100D01*
D02*
G37*
G36*
X-5818D02*
X-7059D01*
Y-201341D01*
X-6539Y-201126D01*
X-6033Y-200620D01*
X-5818Y-200100D01*
D02*
G37*
G36*
X-8059D02*
X-9300D01*
X-9085Y-200620D01*
X-8579Y-201126D01*
X-8059Y-201341D01*
Y-200100D01*
D02*
G37*
G36*
X17941Y-201859D02*
X17421Y-202074D01*
X16915Y-202580D01*
X16703Y-203092D01*
X16179D01*
X15967Y-202580D01*
X15461Y-202074D01*
X14941Y-201859D01*
Y-203600D01*
Y-205341D01*
X15461Y-205126D01*
X15967Y-204620D01*
X16179Y-204108D01*
X16703D01*
X16915Y-204620D01*
X17421Y-205126D01*
X17941Y-205341D01*
Y-203600D01*
Y-201859D01*
D02*
G37*
G36*
X13941D02*
X13421Y-202074D01*
X12915Y-202580D01*
X12703Y-203092D01*
X12179D01*
X11967Y-202580D01*
X11461Y-202074D01*
X10941Y-201859D01*
Y-203600D01*
Y-205341D01*
X11461Y-205126D01*
X11967Y-204620D01*
X12179Y-204108D01*
X12703D01*
X12915Y-204620D01*
X13421Y-205126D01*
X13941Y-205341D01*
Y-203600D01*
Y-201859D01*
D02*
G37*
G36*
X54941D02*
Y-203100D01*
X56182D01*
X55967Y-202580D01*
X55461Y-202074D01*
X54941Y-201859D01*
D02*
G37*
G36*
X53941D02*
X53421Y-202074D01*
X52915Y-202580D01*
X52700Y-203100D01*
X53941D01*
Y-201859D01*
D02*
G37*
G36*
X18941D02*
Y-203100D01*
X20182D01*
X19967Y-202580D01*
X19461Y-202074D01*
X18941Y-201859D01*
D02*
G37*
G36*
X9941D02*
X9421Y-202074D01*
X8915Y-202580D01*
X8700Y-203100D01*
X9941D01*
Y-201859D01*
D02*
G37*
G36*
X81193Y-203967D02*
X80673Y-204183D01*
X80167Y-204689D01*
X79952Y-205209D01*
X81193D01*
Y-203967D01*
D02*
G37*
G36*
X56182Y-204100D02*
X54941D01*
Y-205341D01*
X55461Y-205126D01*
X55967Y-204620D01*
X56182Y-204100D01*
D02*
G37*
G36*
X53941D02*
X52700D01*
X52915Y-204620D01*
X53421Y-205126D01*
X53941Y-205341D01*
Y-204100D01*
D02*
G37*
G36*
X20182D02*
X18941D01*
Y-205341D01*
X19461Y-205126D01*
X19967Y-204620D01*
X20182Y-204100D01*
D02*
G37*
G36*
X9941D02*
X8700D01*
X8915Y-204620D01*
X9421Y-205126D01*
X9941Y-205341D01*
Y-204100D01*
D02*
G37*
G36*
X6866Y-200980D02*
X2035D01*
Y-205811D01*
X2237D01*
X3593Y-205448D01*
X4809Y-204746D01*
X5801Y-203753D01*
X6503Y-202538D01*
X6866Y-201182D01*
Y-200980D01*
D02*
G37*
G36*
X1035D02*
X-3795D01*
Y-201182D01*
X-3432Y-202538D01*
X-2730Y-203753D01*
X-1738Y-204746D01*
X-522Y-205448D01*
X834Y-205811D01*
X1035D01*
Y-200980D01*
D02*
G37*
G36*
X-13134D02*
X-17965D01*
Y-205811D01*
X-17763D01*
X-16407Y-205448D01*
X-15191Y-204746D01*
X-14199Y-203753D01*
X-13497Y-202538D01*
X-13134Y-201182D01*
Y-200980D01*
D02*
G37*
G36*
X-18965D02*
X-23795D01*
Y-201182D01*
X-23432Y-202538D01*
X-22730Y-203753D01*
X-21738Y-204746D01*
X-20522Y-205448D01*
X-19166Y-205811D01*
X-18965D01*
Y-200980D01*
D02*
G37*
G36*
X81193Y-206209D02*
X79952D01*
X80167Y-206728D01*
X80673Y-207235D01*
X81193Y-207450D01*
Y-206209D01*
D02*
G37*
G36*
X49622Y-205323D02*
X44791D01*
Y-207890D01*
X49622D01*
Y-205323D01*
D02*
G37*
G36*
X81488Y-208055D02*
X79315D01*
Y-209146D01*
X81488D01*
Y-208055D01*
D02*
G37*
G36*
X-22059Y-209859D02*
X-22579Y-210074D01*
X-23085Y-210580D01*
X-23297Y-211092D01*
X-23821D01*
X-24033Y-210580D01*
X-24539Y-210074D01*
X-25059Y-209859D01*
Y-211600D01*
Y-213341D01*
X-24539Y-213126D01*
X-24033Y-212620D01*
X-23821Y-212108D01*
X-23297D01*
X-23085Y-212620D01*
X-22579Y-213126D01*
X-22059Y-213341D01*
Y-211600D01*
Y-209859D01*
D02*
G37*
G36*
X-21059D02*
Y-211100D01*
X-19818D01*
X-20033Y-210580D01*
X-20539Y-210074D01*
X-21059Y-209859D01*
D02*
G37*
G36*
X-19818Y-212100D02*
X-21059D01*
Y-213341D01*
X-20539Y-213126D01*
X-20033Y-212620D01*
X-19818Y-212100D01*
D02*
G37*
G36*
X15941Y-213859D02*
X15421Y-214074D01*
X14915Y-214580D01*
X14703Y-215092D01*
X14179D01*
X13967Y-214580D01*
X13461Y-214074D01*
X12941Y-213859D01*
Y-215600D01*
Y-217341D01*
X13461Y-217126D01*
X13967Y-216620D01*
X14179Y-216108D01*
X14703D01*
X14915Y-216620D01*
X15421Y-217126D01*
X15941Y-217341D01*
Y-215600D01*
Y-213859D01*
D02*
G37*
G36*
X55941D02*
X55421Y-214074D01*
X54915Y-214580D01*
X54703Y-215092D01*
X54179D01*
X53967Y-214580D01*
X53461Y-214074D01*
X52941Y-213859D01*
Y-215600D01*
Y-217341D01*
X53461Y-217126D01*
X53967Y-216620D01*
X54179Y-216108D01*
X54703D01*
X54915Y-216620D01*
X55421Y-217126D01*
X55941Y-217341D01*
Y-215600D01*
Y-213859D01*
D02*
G37*
G36*
X56941D02*
Y-215100D01*
X58182D01*
X57967Y-214580D01*
X57461Y-214074D01*
X56941Y-213859D01*
D02*
G37*
G36*
X51941D02*
X51421Y-214074D01*
X50915Y-214580D01*
X50700Y-215100D01*
X51941D01*
Y-213859D01*
D02*
G37*
G36*
X16941D02*
Y-215100D01*
X18182D01*
X17967Y-214580D01*
X17461Y-214074D01*
X16941Y-213859D01*
D02*
G37*
G36*
X11941D02*
X11421Y-214074D01*
X10915Y-214580D01*
X10700Y-215100D01*
X11941D01*
Y-213859D01*
D02*
G37*
G36*
X49622Y-213370D02*
X44791D01*
Y-215937D01*
X49622D01*
Y-213370D01*
D02*
G37*
G36*
X58182Y-216100D02*
X56941D01*
Y-217341D01*
X57461Y-217126D01*
X57967Y-216620D01*
X58182Y-216100D01*
D02*
G37*
G36*
X51941D02*
X50700D01*
X50915Y-216620D01*
X51421Y-217126D01*
X51941Y-217341D01*
Y-216100D01*
D02*
G37*
G36*
X38182D02*
X36941D01*
Y-217341D01*
X37461Y-217126D01*
X37967Y-216620D01*
X38182Y-216100D01*
D02*
G37*
G36*
X35941D02*
X34700D01*
X34915Y-216620D01*
X35421Y-217126D01*
X35941Y-217341D01*
Y-216100D01*
D02*
G37*
G36*
X18182D02*
X16941D01*
Y-217341D01*
X17461Y-217126D01*
X17967Y-216620D01*
X18182Y-216100D01*
D02*
G37*
G36*
X11941D02*
X10700D01*
X10915Y-216620D01*
X11421Y-217126D01*
X11941Y-217341D01*
Y-216100D01*
D02*
G37*
G36*
X82193Y-203967D02*
Y-205709D01*
Y-207450D01*
X82713Y-207235D01*
X83015Y-206932D01*
X84139D01*
X84406Y-207200D01*
Y-208055D01*
X82488D01*
Y-209646D01*
X81988D01*
Y-210146D01*
X79315D01*
Y-211236D01*
X79515D01*
Y-214328D01*
X79209D01*
X78741Y-214421D01*
X78344Y-214686D01*
X77875Y-215155D01*
X77610Y-215552D01*
X77517Y-216020D01*
Y-217982D01*
X77017Y-218334D01*
X77011Y-218332D01*
Y-215551D01*
X76918Y-215083D01*
X76653Y-214686D01*
X74684Y-212718D01*
X74287Y-212452D01*
X73819Y-212359D01*
X72060D01*
Y-208255D01*
X67113D01*
Y-208422D01*
X66929D01*
X66461Y-208515D01*
X66064Y-208781D01*
X65438Y-209406D01*
X63005D01*
Y-208058D01*
X58649D01*
Y-213202D01*
X63005D01*
Y-211853D01*
X65438D01*
X66064Y-212479D01*
X66461Y-212744D01*
X66929Y-212838D01*
X67113D01*
Y-216942D01*
X71180D01*
X71371Y-217404D01*
X69989Y-218787D01*
X65932D01*
Y-220328D01*
X65110D01*
X64883Y-220100D01*
X64295Y-219857D01*
X63658D01*
X63070Y-220100D01*
X62620Y-220550D01*
X62376Y-221138D01*
Y-221775D01*
X62620Y-222363D01*
X63070Y-222813D01*
X63658Y-223057D01*
X64295D01*
X64482Y-222979D01*
X65932D01*
Y-224098D01*
X65732D01*
Y-225979D01*
X65232Y-226073D01*
X64996Y-225836D01*
X64476Y-225621D01*
Y-227362D01*
Y-229103D01*
X64996Y-228888D01*
X65232Y-228652D01*
X65732Y-228745D01*
Y-230232D01*
X68398D01*
Y-227165D01*
X68898D01*
Y-226665D01*
X72063D01*
Y-224098D01*
X71863D01*
Y-220661D01*
X72655Y-219869D01*
X73117Y-220060D01*
Y-224127D01*
X78009D01*
Y-224692D01*
X73117D01*
Y-230032D01*
X74462D01*
Y-231346D01*
X74431Y-231377D01*
X74187Y-231965D01*
Y-232602D01*
X74431Y-233190D01*
X74881Y-233640D01*
X75469Y-233884D01*
X76106D01*
X76694Y-233640D01*
X77144Y-233190D01*
X77387Y-232602D01*
Y-231965D01*
X77144Y-231377D01*
X77113Y-231346D01*
Y-230032D01*
X78009D01*
Y-230807D01*
X78102Y-231275D01*
X78367Y-231672D01*
X79843Y-233149D01*
X80240Y-233414D01*
X80709Y-233507D01*
X81638D01*
X81771Y-233640D01*
X82359Y-233884D01*
X82995D01*
X83583Y-233640D01*
X84034Y-233190D01*
X84277Y-232602D01*
Y-231965D01*
X84034Y-231377D01*
X83583Y-230927D01*
X82995Y-230683D01*
X82359D01*
X81771Y-230927D01*
X81638Y-231060D01*
X81215D01*
X80688Y-230532D01*
X80895Y-230032D01*
X85347D01*
Y-229065D01*
X85457Y-228960D01*
X85847Y-228776D01*
X86296Y-228962D01*
X86932D01*
X87520Y-228719D01*
X87971Y-228269D01*
X88214Y-227680D01*
Y-227044D01*
X87971Y-226456D01*
X87520Y-226006D01*
X86932Y-225762D01*
X86296D01*
X85847Y-225948D01*
X85457Y-225765D01*
X85347Y-225659D01*
Y-224692D01*
X80456D01*
Y-224127D01*
X85347D01*
Y-223160D01*
X85457Y-223054D01*
X85847Y-222871D01*
X86296Y-223057D01*
X86932D01*
X87520Y-222813D01*
X87971Y-222363D01*
X88214Y-221775D01*
Y-221138D01*
X87971Y-220550D01*
X87520Y-220100D01*
X86932Y-219857D01*
X86296D01*
X85847Y-220042D01*
X85457Y-219859D01*
X85347Y-219754D01*
Y-218787D01*
X80753D01*
X79964Y-217997D01*
Y-216942D01*
X84461D01*
Y-215331D01*
X84462Y-215330D01*
X84961Y-215038D01*
X85312Y-215183D01*
X85948D01*
X86536Y-214939D01*
X86986Y-214489D01*
X87230Y-213901D01*
Y-213264D01*
X87008Y-212730D01*
X87469Y-212539D01*
X87919Y-212089D01*
X88162Y-211501D01*
Y-210864D01*
X87919Y-210276D01*
X87469Y-209826D01*
X87020Y-209641D01*
X86966Y-209588D01*
X86787Y-209189D01*
X86770Y-209083D01*
X86853Y-208661D01*
Y-206693D01*
X86760Y-206225D01*
X86495Y-205828D01*
X85511Y-204843D01*
X85114Y-204578D01*
X84646Y-204485D01*
X83015D01*
X82713Y-204183D01*
X82193Y-203967D01*
D02*
G37*
G36*
X17941Y-217859D02*
X17421Y-218074D01*
X16915Y-218580D01*
X16703Y-219092D01*
X16179D01*
X15967Y-218580D01*
X15461Y-218074D01*
X14941Y-217859D01*
Y-219600D01*
Y-221341D01*
X15461Y-221126D01*
X15967Y-220620D01*
X16179Y-220108D01*
X16703D01*
X16915Y-220620D01*
X17421Y-221126D01*
X17941Y-221341D01*
Y-219600D01*
Y-217859D01*
D02*
G37*
G36*
X54941D02*
Y-219100D01*
X56182D01*
X55967Y-218580D01*
X55461Y-218074D01*
X54941Y-217859D01*
D02*
G37*
G36*
X53941D02*
X53421Y-218074D01*
X52915Y-218580D01*
X52700Y-219100D01*
X53941D01*
Y-217859D01*
D02*
G37*
G36*
X34941D02*
Y-219100D01*
X36182D01*
X35967Y-218580D01*
X35461Y-218074D01*
X34941Y-217859D01*
D02*
G37*
G36*
X33941D02*
X33421Y-218074D01*
X32915Y-218580D01*
X32700Y-219100D01*
X33941D01*
Y-217859D01*
D02*
G37*
G36*
X18941D02*
Y-219100D01*
X20182D01*
X19967Y-218580D01*
X19461Y-218074D01*
X18941Y-217859D01*
D02*
G37*
G36*
X13941D02*
X13421Y-218074D01*
X12915Y-218580D01*
X12700Y-219100D01*
X13941D01*
Y-217859D01*
D02*
G37*
G36*
X49622Y-216937D02*
X44291D01*
X38961D01*
Y-219504D01*
X42294D01*
X42572Y-219920D01*
X42550Y-219972D01*
X46033D01*
X46011Y-219920D01*
X46288Y-219504D01*
X49622D01*
Y-216937D01*
D02*
G37*
G36*
X-17763Y-215150D02*
X-17965D01*
Y-219980D01*
X-13134D01*
Y-219778D01*
X-13497Y-218423D01*
X-14199Y-217207D01*
X-15191Y-216215D01*
X-16407Y-215513D01*
X-17763Y-215150D01*
D02*
G37*
G36*
X2237D02*
X2035D01*
Y-219980D01*
X6866D01*
Y-219778D01*
X6503Y-218423D01*
X5801Y-217207D01*
X4809Y-216215D01*
X3593Y-215513D01*
X2237Y-215150D01*
D02*
G37*
G36*
X-18965D02*
X-19166D01*
X-20522Y-215513D01*
X-21738Y-216215D01*
X-22730Y-217207D01*
X-23432Y-218423D01*
X-23795Y-219778D01*
Y-219980D01*
X-18965D01*
Y-215150D01*
D02*
G37*
G36*
X1035D02*
X834D01*
X-522Y-215513D01*
X-1738Y-216215D01*
X-2730Y-217207D01*
X-3432Y-218423D01*
X-3795Y-219778D01*
Y-219980D01*
X1035D01*
Y-215150D01*
D02*
G37*
G36*
X56182Y-220100D02*
X54941D01*
Y-221341D01*
X55461Y-221126D01*
X55967Y-220620D01*
X56182Y-220100D01*
D02*
G37*
G36*
X53941D02*
X52700D01*
X52915Y-220620D01*
X53421Y-221126D01*
X53941Y-221341D01*
Y-220100D01*
D02*
G37*
G36*
X36182D02*
X34941D01*
Y-221341D01*
X35461Y-221126D01*
X35967Y-220620D01*
X36182Y-220100D01*
D02*
G37*
G36*
X33941D02*
X32700D01*
X32915Y-220620D01*
X33421Y-221126D01*
X33941Y-221341D01*
Y-220100D01*
D02*
G37*
G36*
X20182D02*
X18941D01*
Y-221341D01*
X19461Y-221126D01*
X19967Y-220620D01*
X20182Y-220100D01*
D02*
G37*
G36*
X13941D02*
X12700D01*
X12915Y-220620D01*
X13421Y-221126D01*
X13941Y-221341D01*
Y-220100D01*
D02*
G37*
G36*
X46033Y-220972D02*
X44791D01*
Y-222214D01*
X45311Y-221998D01*
X45817Y-221492D01*
X46033Y-220972D01*
D02*
G37*
G36*
X43791D02*
X42550D01*
X42765Y-221492D01*
X43272Y-221998D01*
X43791Y-222214D01*
Y-220972D01*
D02*
G37*
G36*
X39941Y-221859D02*
X39421Y-222074D01*
X38915Y-222580D01*
X38703Y-223092D01*
X38179D01*
X37967Y-222580D01*
X37461Y-222074D01*
X36941Y-221859D01*
Y-223600D01*
Y-225341D01*
X37461Y-225126D01*
X37967Y-224620D01*
X38179Y-224108D01*
X38703D01*
X38915Y-224620D01*
X39421Y-225126D01*
X39941Y-225341D01*
Y-223600D01*
Y-221859D01*
D02*
G37*
G36*
X15941D02*
X15421Y-222074D01*
X14915Y-222580D01*
X14703Y-223092D01*
X14179D01*
X13967Y-222580D01*
X13461Y-222074D01*
X12941Y-221859D01*
Y-223600D01*
Y-225341D01*
X13461Y-225126D01*
X13967Y-224620D01*
X14179Y-224108D01*
X14703D01*
X14915Y-224620D01*
X15421Y-225126D01*
X15941Y-225341D01*
Y-223600D01*
Y-221859D01*
D02*
G37*
G36*
X55941D02*
X55421Y-222074D01*
X54915Y-222580D01*
X54703Y-223092D01*
X54179D01*
X53967Y-222580D01*
X53461Y-222074D01*
X52941Y-221859D01*
Y-223600D01*
Y-225341D01*
X53461Y-225126D01*
X53967Y-224620D01*
X54179Y-224108D01*
X54703D01*
X54915Y-224620D01*
X55421Y-225126D01*
X55941Y-225341D01*
Y-223600D01*
Y-221859D01*
D02*
G37*
G36*
X51941D02*
X51421Y-222074D01*
X50915Y-222580D01*
X50703Y-223092D01*
X50179D01*
X49967Y-222580D01*
X49461Y-222074D01*
X48941Y-221859D01*
Y-223600D01*
Y-225341D01*
X49461Y-225126D01*
X49967Y-224620D01*
X50179Y-224108D01*
X50703D01*
X50915Y-224620D01*
X51421Y-225126D01*
X51941Y-225341D01*
Y-223600D01*
Y-221859D01*
D02*
G37*
G36*
X56941D02*
Y-223100D01*
X58182D01*
X57967Y-222580D01*
X57461Y-222074D01*
X56941Y-221859D01*
D02*
G37*
G36*
X47941D02*
X47421Y-222074D01*
X46915Y-222580D01*
X46700Y-223100D01*
X47941D01*
Y-221859D01*
D02*
G37*
G36*
X40941D02*
Y-223100D01*
X42182D01*
X41967Y-222580D01*
X41461Y-222074D01*
X40941Y-221859D01*
D02*
G37*
G36*
X35941D02*
X35421Y-222074D01*
X34915Y-222580D01*
X34700Y-223100D01*
X35941D01*
Y-221859D01*
D02*
G37*
G36*
X16941D02*
Y-223100D01*
X18182D01*
X17967Y-222580D01*
X17461Y-222074D01*
X16941Y-221859D01*
D02*
G37*
G36*
X11941D02*
X11421Y-222074D01*
X10915Y-222580D01*
X10700Y-223100D01*
X11941D01*
Y-221859D01*
D02*
G37*
G36*
X-7059D02*
Y-223100D01*
X-5818D01*
X-6033Y-222580D01*
X-6539Y-222074D01*
X-7059Y-221859D01*
D02*
G37*
G36*
X-8059D02*
X-8579Y-222074D01*
X-9085Y-222580D01*
X-9300Y-223100D01*
X-8059D01*
Y-221859D01*
D02*
G37*
G36*
X58182Y-224100D02*
X56941D01*
Y-225341D01*
X57461Y-225126D01*
X57967Y-224620D01*
X58182Y-224100D01*
D02*
G37*
G36*
X47941D02*
X46700D01*
X46915Y-224620D01*
X47421Y-225126D01*
X47941Y-225341D01*
Y-224100D01*
D02*
G37*
G36*
X42182D02*
X40941D01*
Y-225341D01*
X41461Y-225126D01*
X41967Y-224620D01*
X42182Y-224100D01*
D02*
G37*
G36*
X35941D02*
X34700D01*
X34915Y-224620D01*
X35421Y-225126D01*
X35941Y-225341D01*
Y-224100D01*
D02*
G37*
G36*
X18182D02*
X16941D01*
Y-225341D01*
X17461Y-225126D01*
X17967Y-224620D01*
X18182Y-224100D01*
D02*
G37*
G36*
X11941D02*
X10700D01*
X10915Y-224620D01*
X11421Y-225126D01*
X11941Y-225341D01*
Y-224100D01*
D02*
G37*
G36*
X-5818D02*
X-7059D01*
Y-225341D01*
X-6539Y-225126D01*
X-6033Y-224620D01*
X-5818Y-224100D01*
D02*
G37*
G36*
X-8059D02*
X-9300D01*
X-9085Y-224620D01*
X-8579Y-225126D01*
X-8059Y-225341D01*
Y-224100D01*
D02*
G37*
G36*
X6866Y-220980D02*
X2035D01*
Y-225811D01*
X2237D01*
X3593Y-225448D01*
X4809Y-224746D01*
X5801Y-223753D01*
X6503Y-222538D01*
X6866Y-221182D01*
Y-220980D01*
D02*
G37*
G36*
X1035D02*
X-3795D01*
Y-221182D01*
X-3432Y-222538D01*
X-2730Y-223753D01*
X-1738Y-224746D01*
X-522Y-225448D01*
X834Y-225811D01*
X1035D01*
Y-220980D01*
D02*
G37*
G36*
X-13134D02*
X-17965D01*
Y-225811D01*
X-17763D01*
X-16407Y-225448D01*
X-15191Y-224746D01*
X-14199Y-223753D01*
X-13497Y-222538D01*
X-13134Y-221182D01*
Y-220980D01*
D02*
G37*
G36*
X-18965D02*
X-23795D01*
Y-221182D01*
X-23432Y-222538D01*
X-22730Y-223753D01*
X-21738Y-224746D01*
X-20522Y-225448D01*
X-19166Y-225811D01*
X-18965D01*
Y-220980D01*
D02*
G37*
G36*
X63476Y-225621D02*
X62957Y-225836D01*
X62450Y-226343D01*
X62235Y-226862D01*
X63476D01*
Y-225621D01*
D02*
G37*
G36*
X41941Y-225859D02*
X41421Y-226074D01*
X40915Y-226580D01*
X40703Y-227092D01*
X40179D01*
X39967Y-226580D01*
X39461Y-226074D01*
X38941Y-225859D01*
Y-227600D01*
Y-229341D01*
X39461Y-229126D01*
X39967Y-228620D01*
X40179Y-228108D01*
X40703D01*
X40915Y-228620D01*
X41421Y-229126D01*
X41941Y-229341D01*
Y-227600D01*
Y-225859D01*
D02*
G37*
G36*
X37941D02*
X37421Y-226074D01*
X36915Y-226580D01*
X36703Y-227092D01*
X36179D01*
X35967Y-226580D01*
X35461Y-226074D01*
X34941Y-225859D01*
Y-227600D01*
Y-229341D01*
X35461Y-229126D01*
X35967Y-228620D01*
X36179Y-228108D01*
X36703D01*
X36915Y-228620D01*
X37421Y-229126D01*
X37941Y-229341D01*
Y-227600D01*
Y-225859D01*
D02*
G37*
G36*
X-6059D02*
X-6579Y-226074D01*
X-7085Y-226580D01*
X-7297Y-227092D01*
X-7821D01*
X-8033Y-226580D01*
X-8539Y-226074D01*
X-9059Y-225859D01*
Y-227600D01*
Y-229341D01*
X-8539Y-229126D01*
X-8033Y-228620D01*
X-7821Y-228108D01*
X-7297D01*
X-7085Y-228620D01*
X-6579Y-229126D01*
X-6059Y-229341D01*
Y-227600D01*
Y-225859D01*
D02*
G37*
G36*
X53941D02*
X53421Y-226074D01*
X52915Y-226580D01*
X52703Y-227092D01*
X52179D01*
X51967Y-226580D01*
X51461Y-226074D01*
X50941Y-225859D01*
Y-227600D01*
Y-229341D01*
X51461Y-229126D01*
X51967Y-228620D01*
X52179Y-228108D01*
X52703D01*
X52915Y-228620D01*
X53421Y-229126D01*
X53941Y-229341D01*
Y-227600D01*
Y-225859D01*
D02*
G37*
G36*
X49941D02*
X49421Y-226074D01*
X48915Y-226580D01*
X48703Y-227092D01*
X48179D01*
X47967Y-226580D01*
X47461Y-226074D01*
X46941Y-225859D01*
Y-227600D01*
Y-229341D01*
X47461Y-229126D01*
X47967Y-228620D01*
X48179Y-228108D01*
X48703D01*
X48915Y-228620D01*
X49421Y-229126D01*
X49941Y-229341D01*
Y-227600D01*
Y-225859D01*
D02*
G37*
G36*
X45941D02*
X45421Y-226074D01*
X44915Y-226580D01*
X44703Y-227092D01*
X44179D01*
X43967Y-226580D01*
X43461Y-226074D01*
X42941Y-225859D01*
Y-227600D01*
Y-229341D01*
X43461Y-229126D01*
X43967Y-228620D01*
X44179Y-228108D01*
X44703D01*
X44915Y-228620D01*
X45421Y-229126D01*
X45941Y-229341D01*
Y-227600D01*
Y-225859D01*
D02*
G37*
G36*
X54941D02*
Y-227100D01*
X56182D01*
X55967Y-226580D01*
X55461Y-226074D01*
X54941Y-225859D01*
D02*
G37*
G36*
X33941D02*
X33421Y-226074D01*
X32915Y-226580D01*
X32700Y-227100D01*
X33941D01*
Y-225859D01*
D02*
G37*
G36*
X10941D02*
Y-227100D01*
X12182D01*
X11967Y-226580D01*
X11461Y-226074D01*
X10941Y-225859D01*
D02*
G37*
G36*
X9941D02*
X9421Y-226074D01*
X8915Y-226580D01*
X8700Y-227100D01*
X9941D01*
Y-225859D01*
D02*
G37*
G36*
X-5059D02*
Y-227100D01*
X-3818D01*
X-4033Y-226580D01*
X-4539Y-226074D01*
X-5059Y-225859D01*
D02*
G37*
G36*
X-10059D02*
X-10579Y-226074D01*
X-11085Y-226580D01*
X-11300Y-227100D01*
X-10059D01*
Y-225859D01*
D02*
G37*
G36*
X-15834Y-227547D02*
X-20977D01*
Y-228206D01*
X-22484D01*
X-22716Y-227974D01*
X-23304Y-227731D01*
X-23940D01*
X-24528Y-227974D01*
X-24979Y-228424D01*
X-25222Y-229012D01*
Y-229649D01*
X-24979Y-230237D01*
X-24528Y-230687D01*
X-23940Y-230931D01*
X-23304D01*
X-22716Y-230687D01*
X-22681Y-230653D01*
X-20977D01*
Y-231287D01*
X-21568D01*
Y-232044D01*
X-22583D01*
X-22716Y-231911D01*
X-23304Y-231668D01*
X-23940D01*
X-24528Y-231911D01*
X-24979Y-232361D01*
X-25222Y-232949D01*
Y-233586D01*
X-24979Y-234174D01*
X-24528Y-234624D01*
X-23940Y-234868D01*
X-23304D01*
X-22716Y-234624D01*
X-22583Y-234491D01*
X-21568D01*
Y-235828D01*
X-22764D01*
X-23304Y-235605D01*
X-23940D01*
X-24528Y-235848D01*
X-24979Y-236298D01*
X-25222Y-236887D01*
Y-237523D01*
X-24979Y-238111D01*
X-24528Y-238561D01*
X-23940Y-238805D01*
X-23304D01*
X-22716Y-238561D01*
X-22430Y-238275D01*
X-21568D01*
Y-238792D01*
X-20977D01*
Y-239702D01*
X-22918D01*
X-23304Y-239542D01*
X-23940D01*
X-24528Y-239785D01*
X-24979Y-240235D01*
X-25222Y-240824D01*
Y-241460D01*
X-24979Y-242048D01*
X-24528Y-242498D01*
X-23940Y-242742D01*
X-23304D01*
X-22716Y-242498D01*
X-22570Y-242352D01*
X-20977D01*
Y-242532D01*
X-15834D01*
Y-238570D01*
X-17802D01*
Y-235249D01*
Y-231509D01*
X-15834D01*
Y-227547D01*
D02*
G37*
G36*
X63476Y-227862D02*
X62235D01*
X62450Y-228382D01*
X62957Y-228888D01*
X63476Y-229103D01*
Y-227862D01*
D02*
G37*
G36*
X56182Y-228100D02*
X54941D01*
Y-229341D01*
X55461Y-229126D01*
X55967Y-228620D01*
X56182Y-228100D01*
D02*
G37*
G36*
X33941D02*
X32700D01*
X32915Y-228620D01*
X33421Y-229126D01*
X33941Y-229341D01*
Y-228100D01*
D02*
G37*
G36*
X12182D02*
X10941D01*
Y-229341D01*
X11461Y-229126D01*
X11967Y-228620D01*
X12182Y-228100D01*
D02*
G37*
G36*
X9941D02*
X8700D01*
X8915Y-228620D01*
X9421Y-229126D01*
X9941Y-229341D01*
Y-228100D01*
D02*
G37*
G36*
X-3818D02*
X-5059D01*
Y-229341D01*
X-4539Y-229126D01*
X-4033Y-228620D01*
X-3818Y-228100D01*
D02*
G37*
G36*
X-10059D02*
X-11300D01*
X-11085Y-228620D01*
X-10579Y-229126D01*
X-10059Y-229341D01*
Y-228100D01*
D02*
G37*
G36*
X72063Y-227665D02*
X69398D01*
Y-230232D01*
X72063D01*
Y-227665D01*
D02*
G37*
G36*
X43941Y-229859D02*
X43421Y-230074D01*
X42915Y-230580D01*
X42703Y-231092D01*
X42179D01*
X41967Y-230580D01*
X41461Y-230074D01*
X40941Y-229859D01*
Y-231600D01*
Y-233341D01*
X41461Y-233126D01*
X41967Y-232620D01*
X42179Y-232108D01*
X42703D01*
X42915Y-232620D01*
X43421Y-233126D01*
X43941Y-233341D01*
Y-231600D01*
Y-229859D01*
D02*
G37*
G36*
X39941D02*
X39421Y-230074D01*
X38915Y-230580D01*
X38703Y-231092D01*
X38179D01*
X37967Y-230580D01*
X37461Y-230074D01*
X36941Y-229859D01*
Y-231600D01*
Y-233341D01*
X37461Y-233126D01*
X37967Y-232620D01*
X38179Y-232108D01*
X38703D01*
X38915Y-232620D01*
X39421Y-233126D01*
X39941Y-233341D01*
Y-231600D01*
Y-229859D01*
D02*
G37*
G36*
X55941D02*
X55421Y-230074D01*
X54915Y-230580D01*
X54703Y-231092D01*
X54179D01*
X53967Y-230580D01*
X53461Y-230074D01*
X52941Y-229859D01*
Y-231600D01*
Y-233341D01*
X53461Y-233126D01*
X53967Y-232620D01*
X54179Y-232108D01*
X54703D01*
X54915Y-232620D01*
X55421Y-233126D01*
X55941Y-233341D01*
Y-231600D01*
Y-229859D01*
D02*
G37*
G36*
X51941D02*
X51421Y-230074D01*
X50915Y-230580D01*
X50703Y-231092D01*
X50179D01*
X49967Y-230580D01*
X49461Y-230074D01*
X48941Y-229859D01*
Y-231600D01*
Y-233341D01*
X49461Y-233126D01*
X49967Y-232620D01*
X50179Y-232108D01*
X50703D01*
X50915Y-232620D01*
X51421Y-233126D01*
X51941Y-233341D01*
Y-231600D01*
Y-229859D01*
D02*
G37*
G36*
X47941D02*
X47421Y-230074D01*
X46915Y-230580D01*
X46703Y-231092D01*
X46179D01*
X45967Y-230580D01*
X45461Y-230074D01*
X44941Y-229859D01*
Y-231600D01*
Y-233341D01*
X45461Y-233126D01*
X45967Y-232620D01*
X46179Y-232108D01*
X46703D01*
X46915Y-232620D01*
X47421Y-233126D01*
X47941Y-233341D01*
Y-231600D01*
Y-229859D01*
D02*
G37*
G36*
X56941D02*
Y-231100D01*
X58182D01*
X57967Y-230580D01*
X57461Y-230074D01*
X56941Y-229859D01*
D02*
G37*
G36*
X35941D02*
X35421Y-230074D01*
X34915Y-230580D01*
X34700Y-231100D01*
X35941D01*
Y-229859D01*
D02*
G37*
G36*
X20941D02*
Y-231100D01*
X22182D01*
X21967Y-230580D01*
X21461Y-230074D01*
X20941Y-229859D01*
D02*
G37*
G36*
X19941D02*
X19421Y-230074D01*
X18915Y-230580D01*
X18700Y-231100D01*
X19941D01*
Y-229859D01*
D02*
G37*
G36*
X58182Y-232100D02*
X56941D01*
Y-233341D01*
X57461Y-233126D01*
X57967Y-232620D01*
X58182Y-232100D01*
D02*
G37*
G36*
X35941D02*
X34700D01*
X34915Y-232620D01*
X35421Y-233126D01*
X35941Y-233341D01*
Y-232100D01*
D02*
G37*
G36*
X22182D02*
X20941D01*
Y-233341D01*
X21461Y-233126D01*
X21967Y-232620D01*
X22182Y-232100D01*
D02*
G37*
G36*
X19941D02*
X18700D01*
X18915Y-232620D01*
X19421Y-233126D01*
X19941Y-233341D01*
Y-232100D01*
D02*
G37*
G36*
X41941Y-233859D02*
X41421Y-234074D01*
X40915Y-234580D01*
X40703Y-235092D01*
X40179D01*
X39967Y-234580D01*
X39461Y-234074D01*
X38941Y-233859D01*
Y-235600D01*
Y-237341D01*
X39461Y-237126D01*
X39967Y-236620D01*
X40179Y-236108D01*
X40703D01*
X40915Y-236620D01*
X41421Y-237126D01*
X41941Y-237341D01*
Y-235600D01*
Y-233859D01*
D02*
G37*
G36*
X37941D02*
X37421Y-234074D01*
X36915Y-234580D01*
X36703Y-235092D01*
X36179D01*
X35967Y-234580D01*
X35461Y-234074D01*
X34941Y-233859D01*
Y-235600D01*
Y-237341D01*
X35461Y-237126D01*
X35967Y-236620D01*
X36179Y-236108D01*
X36703D01*
X36915Y-236620D01*
X37421Y-237126D01*
X37941Y-237341D01*
Y-235600D01*
Y-233859D01*
D02*
G37*
G36*
X21941D02*
X21421Y-234074D01*
X20915Y-234580D01*
X20703Y-235092D01*
X20179D01*
X19967Y-234580D01*
X19461Y-234074D01*
X18941Y-233859D01*
Y-235600D01*
Y-237341D01*
X19461Y-237126D01*
X19967Y-236620D01*
X20179Y-236108D01*
X20703D01*
X20915Y-236620D01*
X21421Y-237126D01*
X21941Y-237341D01*
Y-235600D01*
Y-233859D01*
D02*
G37*
G36*
X53941D02*
X53421Y-234074D01*
X52915Y-234580D01*
X52703Y-235092D01*
X52179D01*
X51967Y-234580D01*
X51461Y-234074D01*
X50941Y-233859D01*
Y-235600D01*
Y-237341D01*
X51461Y-237126D01*
X51967Y-236620D01*
X52179Y-236108D01*
X52703D01*
X52915Y-236620D01*
X53421Y-237126D01*
X53941Y-237341D01*
Y-235600D01*
Y-233859D01*
D02*
G37*
G36*
X49941D02*
X49421Y-234074D01*
X48915Y-234580D01*
X48703Y-235092D01*
X48179D01*
X47967Y-234580D01*
X47461Y-234074D01*
X46941Y-233859D01*
Y-235600D01*
Y-237341D01*
X47461Y-237126D01*
X47967Y-236620D01*
X48179Y-236108D01*
X48703D01*
X48915Y-236620D01*
X49421Y-237126D01*
X49941Y-237341D01*
Y-235600D01*
Y-233859D01*
D02*
G37*
G36*
X45941D02*
X45421Y-234074D01*
X44915Y-234580D01*
X44703Y-235092D01*
X44179D01*
X43967Y-234580D01*
X43461Y-234074D01*
X42941Y-233859D01*
Y-235600D01*
Y-237341D01*
X43461Y-237126D01*
X43967Y-236620D01*
X44179Y-236108D01*
X44703D01*
X44915Y-236620D01*
X45421Y-237126D01*
X45941Y-237341D01*
Y-235600D01*
Y-233859D01*
D02*
G37*
G36*
X54941D02*
Y-235100D01*
X56182D01*
X55967Y-234580D01*
X55461Y-234074D01*
X54941Y-233859D01*
D02*
G37*
G36*
X33941D02*
X33421Y-234074D01*
X32915Y-234580D01*
X32700Y-235100D01*
X33941D01*
Y-233859D01*
D02*
G37*
G36*
X22941D02*
Y-235100D01*
X24182D01*
X23967Y-234580D01*
X23461Y-234074D01*
X22941Y-233859D01*
D02*
G37*
G36*
X17941D02*
X17421Y-234074D01*
X16915Y-234580D01*
X16700Y-235100D01*
X17941D01*
Y-233859D01*
D02*
G37*
G36*
X56182Y-236100D02*
X54941D01*
Y-237341D01*
X55461Y-237126D01*
X55967Y-236620D01*
X56182Y-236100D01*
D02*
G37*
G36*
X33941D02*
X32700D01*
X32915Y-236620D01*
X33421Y-237126D01*
X33941Y-237341D01*
Y-236100D01*
D02*
G37*
G36*
X24182D02*
X22941D01*
Y-237341D01*
X23461Y-237126D01*
X23967Y-236620D01*
X24182Y-236100D01*
D02*
G37*
G36*
X17941D02*
X16700D01*
X16915Y-236620D01*
X17421Y-237126D01*
X17941Y-237341D01*
Y-236100D01*
D02*
G37*
G36*
X41941Y-241859D02*
X41421Y-242074D01*
X40915Y-242580D01*
X40703Y-243092D01*
X40179D01*
X39967Y-242580D01*
X39461Y-242074D01*
X38941Y-241859D01*
Y-243600D01*
Y-245341D01*
X39461Y-245126D01*
X39967Y-244620D01*
X40179Y-244108D01*
X40703D01*
X40915Y-244620D01*
X41421Y-245126D01*
X41941Y-245341D01*
Y-243600D01*
Y-241859D01*
D02*
G37*
G36*
X37941D02*
X37421Y-242074D01*
X36915Y-242580D01*
X36703Y-243092D01*
X36179D01*
X35967Y-242580D01*
X35461Y-242074D01*
X34941Y-241859D01*
Y-243600D01*
Y-245341D01*
X35461Y-245126D01*
X35967Y-244620D01*
X36179Y-244108D01*
X36703D01*
X36915Y-244620D01*
X37421Y-245126D01*
X37941Y-245341D01*
Y-243600D01*
Y-241859D01*
D02*
G37*
G36*
X21941D02*
X21421Y-242074D01*
X20915Y-242580D01*
X20703Y-243092D01*
X20179D01*
X19967Y-242580D01*
X19461Y-242074D01*
X18941Y-241859D01*
Y-243600D01*
Y-245341D01*
X19461Y-245126D01*
X19967Y-244620D01*
X20179Y-244108D01*
X20703D01*
X20915Y-244620D01*
X21421Y-245126D01*
X21941Y-245341D01*
Y-243600D01*
Y-241859D01*
D02*
G37*
G36*
X17941D02*
X17421Y-242074D01*
X16915Y-242580D01*
X16703Y-243092D01*
X16179D01*
X15967Y-242580D01*
X15461Y-242074D01*
X14941Y-241859D01*
Y-243600D01*
Y-245341D01*
X15461Y-245126D01*
X15967Y-244620D01*
X16179Y-244108D01*
X16703D01*
X16915Y-244620D01*
X17421Y-245126D01*
X17941Y-245341D01*
Y-243600D01*
Y-241859D01*
D02*
G37*
G36*
X13941D02*
X13421Y-242074D01*
X12915Y-242580D01*
X12703Y-243092D01*
X12179D01*
X11967Y-242580D01*
X11461Y-242074D01*
X10941Y-241859D01*
Y-243600D01*
Y-245341D01*
X11461Y-245126D01*
X11967Y-244620D01*
X12179Y-244108D01*
X12703D01*
X12915Y-244620D01*
X13421Y-245126D01*
X13941Y-245341D01*
Y-243600D01*
Y-241859D01*
D02*
G37*
G36*
X9941D02*
X9421Y-242074D01*
X8915Y-242580D01*
X8703Y-243092D01*
X8179D01*
X7967Y-242580D01*
X7461Y-242074D01*
X6941Y-241859D01*
Y-243600D01*
Y-245341D01*
X7461Y-245126D01*
X7967Y-244620D01*
X8179Y-244108D01*
X8703D01*
X8915Y-244620D01*
X9421Y-245126D01*
X9941Y-245341D01*
Y-243600D01*
Y-241859D01*
D02*
G37*
G36*
X5941D02*
X5421Y-242074D01*
X4915Y-242580D01*
X4703Y-243092D01*
X4179D01*
X3967Y-242580D01*
X3461Y-242074D01*
X2941Y-241859D01*
Y-243600D01*
Y-245341D01*
X3461Y-245126D01*
X3967Y-244620D01*
X4179Y-244108D01*
X4703D01*
X4915Y-244620D01*
X5421Y-245126D01*
X5941Y-245341D01*
Y-243600D01*
Y-241859D01*
D02*
G37*
G36*
X1941D02*
X1421Y-242074D01*
X915Y-242580D01*
X703Y-243092D01*
X179D01*
X-33Y-242580D01*
X-539Y-242074D01*
X-1059Y-241859D01*
Y-243600D01*
Y-245341D01*
X-539Y-245126D01*
X-33Y-244620D01*
X179Y-244108D01*
X703D01*
X915Y-244620D01*
X1421Y-245126D01*
X1941Y-245341D01*
Y-243600D01*
Y-241859D01*
D02*
G37*
G36*
X-2059D02*
X-2579Y-242074D01*
X-3085Y-242580D01*
X-3297Y-243092D01*
X-3821D01*
X-4033Y-242580D01*
X-4539Y-242074D01*
X-5059Y-241859D01*
Y-243600D01*
Y-245341D01*
X-4539Y-245126D01*
X-4033Y-244620D01*
X-3821Y-244108D01*
X-3297D01*
X-3085Y-244620D01*
X-2579Y-245126D01*
X-2059Y-245341D01*
Y-243600D01*
Y-241859D01*
D02*
G37*
G36*
X-6059D02*
X-6579Y-242074D01*
X-7085Y-242580D01*
X-7297Y-243092D01*
X-7821D01*
X-8033Y-242580D01*
X-8539Y-242074D01*
X-9059Y-241859D01*
Y-243600D01*
Y-245341D01*
X-8539Y-245126D01*
X-8033Y-244620D01*
X-7821Y-244108D01*
X-7297D01*
X-7085Y-244620D01*
X-6579Y-245126D01*
X-6059Y-245341D01*
Y-243600D01*
Y-241859D01*
D02*
G37*
G36*
X-10059D02*
X-10579Y-242074D01*
X-11085Y-242580D01*
X-11297Y-243092D01*
X-11821D01*
X-12033Y-242580D01*
X-12539Y-242074D01*
X-13059Y-241859D01*
Y-243600D01*
Y-245341D01*
X-12539Y-245126D01*
X-12033Y-244620D01*
X-11821Y-244108D01*
X-11297D01*
X-11085Y-244620D01*
X-10579Y-245126D01*
X-10059Y-245341D01*
Y-243600D01*
Y-241859D01*
D02*
G37*
G36*
X53941D02*
X53421Y-242074D01*
X52915Y-242580D01*
X52703Y-243092D01*
X52179D01*
X51967Y-242580D01*
X51461Y-242074D01*
X50941Y-241859D01*
Y-243600D01*
Y-245341D01*
X51461Y-245126D01*
X51967Y-244620D01*
X52179Y-244108D01*
X52703D01*
X52915Y-244620D01*
X53421Y-245126D01*
X53941Y-245341D01*
Y-243600D01*
Y-241859D01*
D02*
G37*
G36*
X49941D02*
X49421Y-242074D01*
X48915Y-242580D01*
X48703Y-243092D01*
X48179D01*
X47967Y-242580D01*
X47461Y-242074D01*
X46941Y-241859D01*
Y-243600D01*
Y-245341D01*
X47461Y-245126D01*
X47967Y-244620D01*
X48179Y-244108D01*
X48703D01*
X48915Y-244620D01*
X49421Y-245126D01*
X49941Y-245341D01*
Y-243600D01*
Y-241859D01*
D02*
G37*
G36*
X45941D02*
X45421Y-242074D01*
X44915Y-242580D01*
X44703Y-243092D01*
X44179D01*
X43967Y-242580D01*
X43461Y-242074D01*
X42941Y-241859D01*
Y-243600D01*
Y-245341D01*
X43461Y-245126D01*
X43967Y-244620D01*
X44179Y-244108D01*
X44703D01*
X44915Y-244620D01*
X45421Y-245126D01*
X45941Y-245341D01*
Y-243600D01*
Y-241859D01*
D02*
G37*
G36*
X54941D02*
Y-243100D01*
X56182D01*
X55967Y-242580D01*
X55461Y-242074D01*
X54941Y-241859D01*
D02*
G37*
G36*
X33941D02*
X33421Y-242074D01*
X32915Y-242580D01*
X32700Y-243100D01*
X33941D01*
Y-241859D01*
D02*
G37*
G36*
X22941D02*
Y-243100D01*
X24182D01*
X23967Y-242580D01*
X23461Y-242074D01*
X22941Y-241859D01*
D02*
G37*
G36*
X-14059D02*
X-14579Y-242074D01*
X-15085Y-242580D01*
X-15300Y-243100D01*
X-14059D01*
Y-241859D01*
D02*
G37*
G36*
X33941Y-244100D02*
X32700D01*
X32915Y-244620D01*
X33421Y-245126D01*
X33941Y-245341D01*
Y-244100D01*
D02*
G37*
G36*
X24182D02*
X22941D01*
Y-245341D01*
X23461Y-245126D01*
X23967Y-244620D01*
X24182Y-244100D01*
D02*
G37*
G36*
X-14059D02*
X-15300D01*
X-15085Y-244620D01*
X-14579Y-245126D01*
X-14059Y-245341D01*
Y-244100D01*
D02*
G37*
G36*
X56182D02*
X54941D01*
Y-245341D01*
X55461Y-245126D01*
X55967Y-244620D01*
X56182Y-244100D01*
D02*
G37*
G36*
X43941Y-245859D02*
X43421Y-246074D01*
X42915Y-246580D01*
X42703Y-247092D01*
X42179D01*
X41967Y-246580D01*
X41461Y-246074D01*
X40941Y-245859D01*
Y-247600D01*
Y-249341D01*
X41461Y-249126D01*
X41967Y-248620D01*
X42179Y-248108D01*
X42703D01*
X42915Y-248620D01*
X43421Y-249126D01*
X43941Y-249341D01*
Y-247600D01*
Y-245859D01*
D02*
G37*
G36*
X39941D02*
X39421Y-246074D01*
X38915Y-246580D01*
X38703Y-247092D01*
X38179D01*
X37967Y-246580D01*
X37461Y-246074D01*
X36941Y-245859D01*
Y-247600D01*
Y-249341D01*
X37461Y-249126D01*
X37967Y-248620D01*
X38179Y-248108D01*
X38703D01*
X38915Y-248620D01*
X39421Y-249126D01*
X39941Y-249341D01*
Y-247600D01*
Y-245859D01*
D02*
G37*
G36*
X19941D02*
X19421Y-246074D01*
X18915Y-246580D01*
X18703Y-247092D01*
X18179D01*
X17967Y-246580D01*
X17461Y-246074D01*
X16941Y-245859D01*
Y-247600D01*
Y-249341D01*
X17461Y-249126D01*
X17967Y-248620D01*
X18179Y-248108D01*
X18703D01*
X18915Y-248620D01*
X19421Y-249126D01*
X19941Y-249341D01*
Y-247600D01*
Y-245859D01*
D02*
G37*
G36*
X15941D02*
X15421Y-246074D01*
X14915Y-246580D01*
X14703Y-247092D01*
X14179D01*
X13967Y-246580D01*
X13461Y-246074D01*
X12941Y-245859D01*
Y-247600D01*
Y-249341D01*
X13461Y-249126D01*
X13967Y-248620D01*
X14179Y-248108D01*
X14703D01*
X14915Y-248620D01*
X15421Y-249126D01*
X15941Y-249341D01*
Y-247600D01*
Y-245859D01*
D02*
G37*
G36*
X11941D02*
X11421Y-246074D01*
X10915Y-246580D01*
X10703Y-247092D01*
X10179D01*
X9967Y-246580D01*
X9461Y-246074D01*
X8941Y-245859D01*
Y-247600D01*
Y-249341D01*
X9461Y-249126D01*
X9967Y-248620D01*
X10179Y-248108D01*
X10703D01*
X10915Y-248620D01*
X11421Y-249126D01*
X11941Y-249341D01*
Y-247600D01*
Y-245859D01*
D02*
G37*
G36*
X-8059D02*
X-8579Y-246074D01*
X-9085Y-246580D01*
X-9297Y-247092D01*
X-9821D01*
X-10033Y-246580D01*
X-10539Y-246074D01*
X-11059Y-245859D01*
Y-247600D01*
Y-249341D01*
X-10539Y-249126D01*
X-10033Y-248620D01*
X-9821Y-248108D01*
X-9297D01*
X-9085Y-248620D01*
X-8579Y-249126D01*
X-8059Y-249341D01*
Y-247600D01*
Y-245859D01*
D02*
G37*
G36*
X55941D02*
X55421Y-246074D01*
X54915Y-246580D01*
X54703Y-247092D01*
X54179D01*
X53967Y-246580D01*
X53461Y-246074D01*
X52941Y-245859D01*
Y-247600D01*
Y-249341D01*
X53461Y-249126D01*
X53967Y-248620D01*
X54179Y-248108D01*
X54703D01*
X54915Y-248620D01*
X55421Y-249126D01*
X55941Y-249341D01*
Y-247600D01*
Y-245859D01*
D02*
G37*
G36*
X51941D02*
X51421Y-246074D01*
X50915Y-246580D01*
X50703Y-247092D01*
X50179D01*
X49967Y-246580D01*
X49461Y-246074D01*
X48941Y-245859D01*
Y-247600D01*
Y-249341D01*
X49461Y-249126D01*
X49967Y-248620D01*
X50179Y-248108D01*
X50703D01*
X50915Y-248620D01*
X51421Y-249126D01*
X51941Y-249341D01*
Y-247600D01*
Y-245859D01*
D02*
G37*
G36*
X47941D02*
X47421Y-246074D01*
X46915Y-246580D01*
X46703Y-247092D01*
X46179D01*
X45967Y-246580D01*
X45461Y-246074D01*
X44941Y-245859D01*
Y-247600D01*
Y-249341D01*
X45461Y-249126D01*
X45967Y-248620D01*
X46179Y-248108D01*
X46703D01*
X46915Y-248620D01*
X47421Y-249126D01*
X47941Y-249341D01*
Y-247600D01*
Y-245859D01*
D02*
G37*
G36*
X56941D02*
Y-247100D01*
X58182D01*
X57967Y-246580D01*
X57461Y-246074D01*
X56941Y-245859D01*
D02*
G37*
G36*
X35941D02*
X35421Y-246074D01*
X34915Y-246580D01*
X34700Y-247100D01*
X35941D01*
Y-245859D01*
D02*
G37*
G36*
X20941D02*
Y-247100D01*
X22182D01*
X21967Y-246580D01*
X21461Y-246074D01*
X20941Y-245859D01*
D02*
G37*
G36*
X7941D02*
X7421Y-246074D01*
X6915Y-246580D01*
X6700Y-247100D01*
X7941D01*
Y-245859D01*
D02*
G37*
G36*
X-7059D02*
Y-247100D01*
X-5818D01*
X-6033Y-246580D01*
X-6539Y-246074D01*
X-7059Y-245859D01*
D02*
G37*
G36*
X-12059D02*
X-12579Y-246074D01*
X-13085Y-246580D01*
X-13300Y-247100D01*
X-12059D01*
Y-245859D01*
D02*
G37*
G36*
X58182Y-248100D02*
X56941D01*
Y-249341D01*
X57461Y-249126D01*
X57967Y-248620D01*
X58182Y-248100D01*
D02*
G37*
G36*
X35941D02*
X34700D01*
X34915Y-248620D01*
X35421Y-249126D01*
X35941Y-249341D01*
Y-248100D01*
D02*
G37*
G36*
X22182D02*
X20941D01*
Y-249341D01*
X21461Y-249126D01*
X21967Y-248620D01*
X22182Y-248100D01*
D02*
G37*
G36*
X7941D02*
X6700D01*
X6915Y-248620D01*
X7421Y-249126D01*
X7941Y-249341D01*
Y-248100D01*
D02*
G37*
G36*
X-5818D02*
X-7059D01*
Y-249341D01*
X-6539Y-249126D01*
X-6033Y-248620D01*
X-5818Y-248100D01*
D02*
G37*
G36*
X-12059D02*
X-13300D01*
X-13085Y-248620D01*
X-12579Y-249126D01*
X-12059Y-249341D01*
Y-248100D01*
D02*
G37*
G36*
X37941Y-249859D02*
X37421Y-250074D01*
X36915Y-250580D01*
X36703Y-251092D01*
X36179D01*
X35967Y-250580D01*
X35461Y-250074D01*
X34941Y-249859D01*
Y-251600D01*
Y-253341D01*
X35461Y-253126D01*
X35967Y-252620D01*
X36179Y-252108D01*
X36703D01*
X36915Y-252620D01*
X37421Y-253126D01*
X37941Y-253341D01*
Y-251600D01*
Y-249859D01*
D02*
G37*
G36*
X21941D02*
X21421Y-250074D01*
X20915Y-250580D01*
X20703Y-251092D01*
X20179D01*
X19967Y-250580D01*
X19461Y-250074D01*
X18941Y-249859D01*
Y-251600D01*
Y-253341D01*
X19461Y-253126D01*
X19967Y-252620D01*
X20179Y-252108D01*
X20703D01*
X20915Y-252620D01*
X21421Y-253126D01*
X21941Y-253341D01*
Y-251600D01*
Y-249859D01*
D02*
G37*
G36*
X17941D02*
X17421Y-250074D01*
X16915Y-250580D01*
X16703Y-251092D01*
X16179D01*
X15967Y-250580D01*
X15461Y-250074D01*
X14941Y-249859D01*
Y-251600D01*
Y-253341D01*
X15461Y-253126D01*
X15967Y-252620D01*
X16179Y-252108D01*
X16703D01*
X16915Y-252620D01*
X17421Y-253126D01*
X17941Y-253341D01*
Y-251600D01*
Y-249859D01*
D02*
G37*
G36*
X13941D02*
X13421Y-250074D01*
X12915Y-250580D01*
X12703Y-251092D01*
X12179D01*
X11967Y-250580D01*
X11461Y-250074D01*
X10941Y-249859D01*
Y-251600D01*
Y-253341D01*
X11461Y-253126D01*
X11967Y-252620D01*
X12179Y-252108D01*
X12703D01*
X12915Y-252620D01*
X13421Y-253126D01*
X13941Y-253341D01*
Y-251600D01*
Y-249859D01*
D02*
G37*
G36*
X53941D02*
X53421Y-250074D01*
X52915Y-250580D01*
X52703Y-251092D01*
X52179D01*
X51967Y-250580D01*
X51461Y-250074D01*
X50941Y-249859D01*
Y-251600D01*
Y-253341D01*
X51461Y-253126D01*
X51967Y-252620D01*
X52179Y-252108D01*
X52703D01*
X52915Y-252620D01*
X53421Y-253126D01*
X53941Y-253341D01*
Y-251600D01*
Y-249859D01*
D02*
G37*
G36*
X54941D02*
Y-251100D01*
X56182D01*
X55967Y-250580D01*
X55461Y-250074D01*
X54941Y-249859D01*
D02*
G37*
G36*
X49941D02*
X49421Y-250074D01*
X48915Y-250580D01*
X48700Y-251100D01*
X49941D01*
Y-249859D01*
D02*
G37*
G36*
X38941D02*
Y-251100D01*
X40182D01*
X39967Y-250580D01*
X39461Y-250074D01*
X38941Y-249859D01*
D02*
G37*
G36*
X33941D02*
X33421Y-250074D01*
X32915Y-250580D01*
X32700Y-251100D01*
X33941D01*
Y-249859D01*
D02*
G37*
G36*
X22941D02*
Y-251100D01*
X24182D01*
X23967Y-250580D01*
X23461Y-250074D01*
X22941Y-249859D01*
D02*
G37*
G36*
X9941D02*
X9421Y-250074D01*
X8915Y-250580D01*
X8700Y-251100D01*
X9941D01*
Y-249859D01*
D02*
G37*
G36*
X-9059D02*
Y-251100D01*
X-7818D01*
X-8033Y-250580D01*
X-8539Y-250074D01*
X-9059Y-249859D01*
D02*
G37*
G36*
X-10059D02*
X-10579Y-250074D01*
X-11085Y-250580D01*
X-11300Y-251100D01*
X-10059D01*
Y-249859D01*
D02*
G37*
G36*
X44791Y-251212D02*
Y-252453D01*
X46033D01*
X45817Y-251933D01*
X45311Y-251427D01*
X44791Y-251212D01*
D02*
G37*
G36*
X43791D02*
X43272Y-251427D01*
X42765Y-251933D01*
X42550Y-252453D01*
X43791D01*
Y-251212D01*
D02*
G37*
G36*
X2237Y-248299D02*
X2035D01*
Y-253130D01*
X6866D01*
Y-252928D01*
X6503Y-251572D01*
X5801Y-250357D01*
X4809Y-249364D01*
X3593Y-248662D01*
X2237Y-248299D01*
D02*
G37*
G36*
X-17763D02*
X-17965D01*
Y-253130D01*
X-13134D01*
Y-252928D01*
X-13497Y-251572D01*
X-14199Y-250357D01*
X-15191Y-249364D01*
X-16407Y-248662D01*
X-17763Y-248299D01*
D02*
G37*
G36*
X-18965D02*
X-19166D01*
X-20522Y-248662D01*
X-21738Y-249364D01*
X-22730Y-250357D01*
X-23432Y-251572D01*
X-23795Y-252928D01*
Y-253130D01*
X-18965D01*
Y-248299D01*
D02*
G37*
G36*
X1035D02*
X834D01*
X-522Y-248662D01*
X-1738Y-249364D01*
X-2730Y-250357D01*
X-3432Y-251572D01*
X-3795Y-252928D01*
Y-253130D01*
X1035D01*
Y-248299D01*
D02*
G37*
G36*
X40182Y-252100D02*
X38941D01*
Y-253341D01*
X39461Y-253126D01*
X39967Y-252620D01*
X40182Y-252100D01*
D02*
G37*
G36*
X33941D02*
X32700D01*
X32915Y-252620D01*
X33421Y-253126D01*
X33941Y-253341D01*
Y-252100D01*
D02*
G37*
G36*
X24182D02*
X22941D01*
Y-253341D01*
X23461Y-253126D01*
X23967Y-252620D01*
X24182Y-252100D01*
D02*
G37*
G36*
X9941D02*
X8700D01*
X8915Y-252620D01*
X9421Y-253126D01*
X9941Y-253341D01*
Y-252100D01*
D02*
G37*
G36*
X-7818D02*
X-9059D01*
Y-253341D01*
X-8539Y-253126D01*
X-8033Y-252620D01*
X-7818Y-252100D01*
D02*
G37*
G36*
X-10059D02*
X-11300D01*
X-11085Y-252620D01*
X-10579Y-253126D01*
X-10059Y-253341D01*
Y-252100D01*
D02*
G37*
G36*
X56182D02*
X54941D01*
Y-253341D01*
X55461Y-253126D01*
X55967Y-252620D01*
X56182Y-252100D01*
D02*
G37*
G36*
X49941D02*
X48700D01*
X48915Y-252620D01*
X49421Y-253126D01*
X49941Y-253341D01*
Y-252100D01*
D02*
G37*
G36*
X19941Y-253859D02*
X19421Y-254074D01*
X18915Y-254580D01*
X18703Y-255092D01*
X18179D01*
X17967Y-254580D01*
X17461Y-254074D01*
X16941Y-253859D01*
Y-255600D01*
Y-257341D01*
X17461Y-257126D01*
X17967Y-256620D01*
X18179Y-256108D01*
X18703D01*
X18915Y-256620D01*
X19421Y-257126D01*
X19941Y-257341D01*
Y-255600D01*
Y-253859D01*
D02*
G37*
G36*
X15941D02*
X15421Y-254074D01*
X14915Y-254580D01*
X14703Y-255092D01*
X14179D01*
X13967Y-254580D01*
X13461Y-254074D01*
X12941Y-253859D01*
Y-255600D01*
Y-257341D01*
X13461Y-257126D01*
X13967Y-256620D01*
X14179Y-256108D01*
X14703D01*
X14915Y-256620D01*
X15421Y-257126D01*
X15941Y-257341D01*
Y-255600D01*
Y-253859D01*
D02*
G37*
G36*
X55941D02*
X55421Y-254074D01*
X54915Y-254580D01*
X54703Y-255092D01*
X54179D01*
X53967Y-254580D01*
X53461Y-254074D01*
X52941Y-253859D01*
Y-255600D01*
Y-257341D01*
X53461Y-257126D01*
X53967Y-256620D01*
X54179Y-256108D01*
X54703D01*
X54915Y-256620D01*
X55421Y-257126D01*
X55941Y-257341D01*
Y-255600D01*
Y-253859D01*
D02*
G37*
G36*
X56941D02*
Y-255100D01*
X58182D01*
X57967Y-254580D01*
X57461Y-254074D01*
X56941Y-253859D01*
D02*
G37*
G36*
X51941D02*
X51421Y-254074D01*
X50915Y-254580D01*
X50700Y-255100D01*
X51941D01*
Y-253859D01*
D02*
G37*
G36*
X36941D02*
Y-255100D01*
X38182D01*
X37967Y-254580D01*
X37461Y-254074D01*
X36941Y-253859D01*
D02*
G37*
G36*
X35941D02*
X35421Y-254074D01*
X34915Y-254580D01*
X34700Y-255100D01*
X35941D01*
Y-253859D01*
D02*
G37*
G36*
X20941D02*
Y-255100D01*
X22182D01*
X21967Y-254580D01*
X21461Y-254074D01*
X20941Y-253859D01*
D02*
G37*
G36*
X11941D02*
X11421Y-254074D01*
X10915Y-254580D01*
X10700Y-255100D01*
X11941D01*
Y-253859D01*
D02*
G37*
G36*
X46033Y-253453D02*
X42550D01*
X42572Y-253505D01*
X42294Y-253921D01*
X38961D01*
Y-256488D01*
X44291D01*
X49622D01*
Y-253921D01*
X46288D01*
X46011Y-253505D01*
X46033Y-253453D01*
D02*
G37*
G36*
X58182Y-256100D02*
X56941D01*
Y-257341D01*
X57461Y-257126D01*
X57967Y-256620D01*
X58182Y-256100D01*
D02*
G37*
G36*
X51941D02*
X50700D01*
X50915Y-256620D01*
X51421Y-257126D01*
X51941Y-257341D01*
Y-256100D01*
D02*
G37*
G36*
X38182D02*
X36941D01*
Y-257341D01*
X37461Y-257126D01*
X37967Y-256620D01*
X38182Y-256100D01*
D02*
G37*
G36*
X35941D02*
X34700D01*
X34915Y-256620D01*
X35421Y-257126D01*
X35941Y-257341D01*
Y-256100D01*
D02*
G37*
G36*
X22182D02*
X20941D01*
Y-257341D01*
X21461Y-257126D01*
X21967Y-256620D01*
X22182Y-256100D01*
D02*
G37*
G36*
X11941D02*
X10700D01*
X10915Y-256620D01*
X11421Y-257126D01*
X11941Y-257341D01*
Y-256100D01*
D02*
G37*
G36*
X87114Y-257117D02*
Y-258358D01*
X88355D01*
X88140Y-257839D01*
X87634Y-257332D01*
X87114Y-257117D01*
D02*
G37*
G36*
X86114D02*
X85595Y-257332D01*
X85088Y-257839D01*
X84873Y-258358D01*
X86114D01*
Y-257117D01*
D02*
G37*
G36*
X6866Y-254130D02*
X2035D01*
Y-258961D01*
X2237D01*
X3593Y-258597D01*
X4809Y-257896D01*
X5801Y-256903D01*
X6503Y-255687D01*
X6866Y-254332D01*
Y-254130D01*
D02*
G37*
G36*
X1035D02*
X-3795D01*
Y-254332D01*
X-3432Y-255687D01*
X-2730Y-256903D01*
X-1738Y-257896D01*
X-522Y-258597D01*
X834Y-258961D01*
X1035D01*
Y-254130D01*
D02*
G37*
G36*
X-13134D02*
X-17965D01*
Y-258961D01*
X-17763D01*
X-16407Y-258597D01*
X-15191Y-257896D01*
X-14199Y-256903D01*
X-13497Y-255687D01*
X-13134Y-254332D01*
Y-254130D01*
D02*
G37*
G36*
X-18965D02*
X-23795D01*
Y-254332D01*
X-23432Y-255687D01*
X-22730Y-256903D01*
X-21738Y-257896D01*
X-20522Y-258597D01*
X-19166Y-258961D01*
X-18965D01*
Y-254130D01*
D02*
G37*
G36*
X21941Y-257859D02*
X21421Y-258074D01*
X20915Y-258580D01*
X20703Y-259092D01*
X20179D01*
X19967Y-258580D01*
X19461Y-258074D01*
X18941Y-257859D01*
Y-259600D01*
Y-261341D01*
X19461Y-261126D01*
X19967Y-260620D01*
X20179Y-260108D01*
X20703D01*
X20915Y-260620D01*
X21421Y-261126D01*
X21941Y-261341D01*
Y-259600D01*
Y-257859D01*
D02*
G37*
G36*
X17941D02*
X17421Y-258074D01*
X16915Y-258580D01*
X16703Y-259092D01*
X16179D01*
X15967Y-258580D01*
X15461Y-258074D01*
X14941Y-257859D01*
Y-259600D01*
Y-261341D01*
X15461Y-261126D01*
X15967Y-260620D01*
X16179Y-260108D01*
X16703D01*
X16915Y-260620D01*
X17421Y-261126D01*
X17941Y-261341D01*
Y-259600D01*
Y-257859D01*
D02*
G37*
G36*
X13941D02*
X13421Y-258074D01*
X12915Y-258580D01*
X12703Y-259092D01*
X12179D01*
X11967Y-258580D01*
X11461Y-258074D01*
X10941Y-257859D01*
Y-259600D01*
Y-261341D01*
X11461Y-261126D01*
X11967Y-260620D01*
X12179Y-260108D01*
X12703D01*
X12915Y-260620D01*
X13421Y-261126D01*
X13941Y-261341D01*
Y-259600D01*
Y-257859D01*
D02*
G37*
G36*
X22941D02*
Y-259100D01*
X24182D01*
X23967Y-258580D01*
X23461Y-258074D01*
X22941Y-257859D01*
D02*
G37*
G36*
X9941D02*
X9421Y-258074D01*
X8915Y-258580D01*
X8700Y-259100D01*
X9941D01*
Y-257859D01*
D02*
G37*
G36*
X-25059D02*
Y-259100D01*
X-23818D01*
X-24033Y-258580D01*
X-24539Y-258074D01*
X-25059Y-257859D01*
D02*
G37*
G36*
X49622Y-257488D02*
X44791D01*
Y-260055D01*
X49622D01*
Y-257488D01*
D02*
G37*
G36*
X81488Y-260221D02*
X79315D01*
Y-261311D01*
X81488D01*
Y-260221D01*
D02*
G37*
G36*
X24182Y-260100D02*
X22941D01*
Y-261341D01*
X23461Y-261126D01*
X23967Y-260620D01*
X24182Y-260100D01*
D02*
G37*
G36*
X9941D02*
X8700D01*
X8915Y-260620D01*
X9421Y-261126D01*
X9941Y-261341D01*
Y-260100D01*
D02*
G37*
G36*
X-23818D02*
X-25059D01*
Y-261341D01*
X-24539Y-261126D01*
X-24033Y-260620D01*
X-23818Y-260100D01*
D02*
G37*
G36*
X43791Y-257488D02*
X38961D01*
Y-260027D01*
X35421D01*
Y-262406D01*
X-3728D01*
Y-258893D01*
X-13202D01*
Y-268367D01*
X-3728D01*
Y-264853D01*
X35067D01*
X35421Y-265207D01*
X35420Y-265516D01*
X35064Y-265910D01*
X34941Y-265859D01*
Y-267100D01*
X36182D01*
X35967Y-266580D01*
X35528Y-266142D01*
X35461Y-266074D01*
X35444Y-266024D01*
X35535Y-265564D01*
X35894Y-265564D01*
X35894Y-265564D01*
X35901Y-265564D01*
X36966D01*
Y-279515D01*
X35421D01*
Y-286627D01*
X40957D01*
Y-279515D01*
X39413D01*
Y-271669D01*
X42294D01*
X42572Y-272085D01*
X42550Y-272138D01*
X46033D01*
X46011Y-272085D01*
X46288Y-271669D01*
X49622D01*
Y-269102D01*
X44291D01*
Y-268602D01*
X43791D01*
Y-265535D01*
X41154D01*
Y-264019D01*
X53137D01*
Y-265367D01*
X53822D01*
X53921Y-265867D01*
X53421Y-266074D01*
X52915Y-266580D01*
X52700Y-267100D01*
X56182D01*
X55967Y-266580D01*
X55461Y-266074D01*
X54961Y-265867D01*
X55060Y-265367D01*
X57493D01*
Y-260224D01*
X53137D01*
Y-261572D01*
X41154D01*
Y-260055D01*
X43791D01*
Y-257488D01*
D02*
G37*
G36*
X-20059Y-261859D02*
X-20579Y-262074D01*
X-21085Y-262580D01*
X-21297Y-263092D01*
X-21821D01*
X-22033Y-262580D01*
X-22539Y-262074D01*
X-23059Y-261859D01*
Y-263600D01*
Y-265341D01*
X-22539Y-265126D01*
X-22033Y-264620D01*
X-21821Y-264108D01*
X-21297D01*
X-21085Y-264620D01*
X-20579Y-265126D01*
X-20059Y-265341D01*
Y-263600D01*
Y-261859D01*
D02*
G37*
G36*
X-19059D02*
Y-263100D01*
X-17818D01*
X-18033Y-262580D01*
X-18539Y-262074D01*
X-19059Y-261859D01*
D02*
G37*
G36*
X-24059D02*
X-24579Y-262074D01*
X-25085Y-262580D01*
X-25300Y-263100D01*
X-24059D01*
Y-261859D01*
D02*
G37*
G36*
X-17818Y-264100D02*
X-19059D01*
Y-265341D01*
X-18539Y-265126D01*
X-18033Y-264620D01*
X-17818Y-264100D01*
D02*
G37*
G36*
X-24059D02*
X-25300D01*
X-25085Y-264620D01*
X-24579Y-265126D01*
X-24059Y-265341D01*
Y-264100D01*
D02*
G37*
G36*
X21941Y-265859D02*
X21421Y-266074D01*
X20915Y-266580D01*
X20703Y-267092D01*
X20179D01*
X19967Y-266580D01*
X19461Y-266074D01*
X18941Y-265859D01*
Y-267600D01*
Y-269341D01*
X19461Y-269126D01*
X19967Y-268620D01*
X20179Y-268108D01*
X20703D01*
X20915Y-268620D01*
X21421Y-269126D01*
X21941Y-269341D01*
Y-267600D01*
Y-265859D01*
D02*
G37*
G36*
X17941D02*
X17421Y-266074D01*
X16915Y-266580D01*
X16703Y-267092D01*
X16179D01*
X15967Y-266580D01*
X15461Y-266074D01*
X14941Y-265859D01*
Y-267600D01*
Y-269341D01*
X15461Y-269126D01*
X15967Y-268620D01*
X16179Y-268108D01*
X16703D01*
X16915Y-268620D01*
X17421Y-269126D01*
X17941Y-269341D01*
Y-267600D01*
Y-265859D01*
D02*
G37*
G36*
X13941D02*
X13421Y-266074D01*
X12915Y-266580D01*
X12703Y-267092D01*
X12179D01*
X11967Y-266580D01*
X11461Y-266074D01*
X10941Y-265859D01*
Y-267600D01*
Y-269341D01*
X11461Y-269126D01*
X11967Y-268620D01*
X12179Y-268108D01*
X12703D01*
X12915Y-268620D01*
X13421Y-269126D01*
X13941Y-269341D01*
Y-267600D01*
Y-265859D01*
D02*
G37*
G36*
X33941D02*
X33421Y-266074D01*
X32915Y-266580D01*
X32700Y-267100D01*
X33941D01*
Y-265859D01*
D02*
G37*
G36*
X22941D02*
Y-267100D01*
X24182D01*
X23967Y-266580D01*
X23461Y-266074D01*
X22941Y-265859D01*
D02*
G37*
G36*
X9941D02*
X9421Y-266074D01*
X8915Y-266580D01*
X8700Y-267100D01*
X9941D01*
Y-265859D01*
D02*
G37*
G36*
X-25059D02*
Y-267100D01*
X-23818D01*
X-24033Y-266580D01*
X-24539Y-266074D01*
X-25059Y-265859D01*
D02*
G37*
G36*
X49622Y-265535D02*
X44791D01*
Y-268102D01*
X49622D01*
Y-265535D01*
D02*
G37*
G36*
X56182Y-268100D02*
X54941D01*
Y-269341D01*
X55461Y-269126D01*
X55967Y-268620D01*
X56182Y-268100D01*
D02*
G37*
G36*
X53941D02*
X52700D01*
X52915Y-268620D01*
X53421Y-269126D01*
X53941Y-269341D01*
Y-268100D01*
D02*
G37*
G36*
X36182D02*
X34941D01*
Y-269341D01*
X35461Y-269126D01*
X35967Y-268620D01*
X36182Y-268100D01*
D02*
G37*
G36*
X33941D02*
X32700D01*
X32915Y-268620D01*
X33421Y-269126D01*
X33941Y-269341D01*
Y-268100D01*
D02*
G37*
G36*
X24182D02*
X22941D01*
Y-269341D01*
X23461Y-269126D01*
X23967Y-268620D01*
X24182Y-268100D01*
D02*
G37*
G36*
X9941D02*
X8700D01*
X8915Y-268620D01*
X9421Y-269126D01*
X9941Y-269341D01*
Y-268100D01*
D02*
G37*
G36*
X-23818D02*
X-25059D01*
Y-269341D01*
X-24539Y-269126D01*
X-24033Y-268620D01*
X-23818Y-268100D01*
D02*
G37*
G36*
X19941Y-269859D02*
X19421Y-270074D01*
X18915Y-270580D01*
X18703Y-271092D01*
X18179D01*
X17967Y-270580D01*
X17461Y-270074D01*
X16941Y-269859D01*
Y-271600D01*
Y-273341D01*
X17461Y-273126D01*
X17967Y-272620D01*
X18179Y-272108D01*
X18703D01*
X18915Y-272620D01*
X19421Y-273126D01*
X19941Y-273341D01*
Y-271600D01*
Y-269859D01*
D02*
G37*
G36*
X15941D02*
X15421Y-270074D01*
X14915Y-270580D01*
X14703Y-271092D01*
X14179D01*
X13967Y-270580D01*
X13461Y-270074D01*
X12941Y-269859D01*
Y-271600D01*
Y-273341D01*
X13461Y-273126D01*
X13967Y-272620D01*
X14179Y-272108D01*
X14703D01*
X14915Y-272620D01*
X15421Y-273126D01*
X15941Y-273341D01*
Y-271600D01*
Y-269859D01*
D02*
G37*
G36*
X55941D02*
X55421Y-270074D01*
X54915Y-270580D01*
X54703Y-271092D01*
X54179D01*
X53967Y-270580D01*
X53461Y-270074D01*
X52941Y-269859D01*
Y-271600D01*
Y-273341D01*
X53461Y-273126D01*
X53967Y-272620D01*
X54179Y-272108D01*
X54703D01*
X54915Y-272620D01*
X55421Y-273126D01*
X55941Y-273341D01*
Y-271600D01*
Y-269859D01*
D02*
G37*
G36*
X56941D02*
Y-271100D01*
X58182D01*
X57967Y-270580D01*
X57461Y-270074D01*
X56941Y-269859D01*
D02*
G37*
G36*
X51941D02*
X51421Y-270074D01*
X50915Y-270580D01*
X50700Y-271100D01*
X51941D01*
Y-269859D01*
D02*
G37*
G36*
X20941D02*
Y-271100D01*
X22182D01*
X21967Y-270580D01*
X21461Y-270074D01*
X20941Y-269859D01*
D02*
G37*
G36*
X11941D02*
X11421Y-270074D01*
X10915Y-270580D01*
X10700Y-271100D01*
X11941D01*
Y-269859D01*
D02*
G37*
G36*
X88355Y-259358D02*
X84655D01*
X84500Y-259591D01*
X84406Y-260059D01*
Y-260221D01*
X82488D01*
Y-261811D01*
X81988D01*
Y-262311D01*
X79315D01*
Y-263402D01*
X79515D01*
Y-266687D01*
X79066Y-266777D01*
X78669Y-267042D01*
X77875Y-267836D01*
X77610Y-268233D01*
X77517Y-268701D01*
Y-271654D01*
X77610Y-272122D01*
X77809Y-272421D01*
X77645Y-272920D01*
X77011D01*
Y-266732D01*
X76918Y-266264D01*
X76652Y-265867D01*
X75668Y-264883D01*
X75271Y-264618D01*
X74803Y-264525D01*
X72060D01*
Y-260420D01*
X67113D01*
Y-260588D01*
X66713D01*
X66245Y-260681D01*
X65848Y-260946D01*
X65222Y-261572D01*
X63005D01*
Y-260224D01*
X58649D01*
Y-265367D01*
X63005D01*
Y-264019D01*
X65222D01*
X65848Y-264645D01*
X66245Y-264910D01*
X66713Y-265003D01*
X67113D01*
Y-269107D01*
X72060D01*
Y-269107D01*
X72493Y-269267D01*
Y-270415D01*
X69989Y-272920D01*
X65932D01*
Y-274265D01*
X64914D01*
X64883Y-274234D01*
X64295Y-273991D01*
X63658D01*
X63070Y-274234D01*
X62620Y-274684D01*
X62376Y-275272D01*
Y-275909D01*
X62620Y-276497D01*
X63070Y-276947D01*
X63658Y-277190D01*
X64295D01*
X64883Y-276947D01*
X64914Y-276916D01*
X65932D01*
Y-278232D01*
X65732D01*
Y-280799D01*
X72063D01*
Y-278232D01*
X71863D01*
Y-274795D01*
X72655Y-274003D01*
X73117Y-274194D01*
Y-278261D01*
X77898D01*
X78064Y-278543D01*
X77898Y-278826D01*
X73117D01*
Y-284166D01*
X74085D01*
X74190Y-284276D01*
X74373Y-284666D01*
X74187Y-285115D01*
Y-285751D01*
X74431Y-286339D01*
X74881Y-286789D01*
X75469Y-287033D01*
X76106D01*
X76694Y-286789D01*
X77144Y-286339D01*
X77387Y-285751D01*
Y-285115D01*
X77202Y-284666D01*
X77385Y-284276D01*
X77490Y-284166D01*
X78457Y-284166D01*
X78501Y-284648D01*
Y-285433D01*
X78594Y-285901D01*
X78859Y-286298D01*
X80280Y-287719D01*
Y-287901D01*
X80523Y-288489D01*
X80973Y-288939D01*
X81561Y-289182D01*
X82198D01*
X82786Y-288939D01*
X83236Y-288489D01*
X83480Y-287901D01*
Y-287264D01*
X83236Y-286676D01*
X82786Y-286226D01*
X82198Y-285982D01*
X82004D01*
X80948Y-284926D01*
Y-284648D01*
X80991Y-284166D01*
X81448Y-284166D01*
X86331D01*
Y-283199D01*
X86441Y-283094D01*
X86831Y-282910D01*
X87280Y-283096D01*
X87917D01*
X88505Y-282853D01*
X88955Y-282402D01*
X89198Y-281814D01*
Y-281178D01*
X88955Y-280590D01*
X88505Y-280140D01*
X87917Y-279896D01*
X87280D01*
X86831Y-280082D01*
X86441Y-279899D01*
X86331Y-279793D01*
Y-278826D01*
X81551Y-278826D01*
X81385Y-278543D01*
X81551Y-278261D01*
X86331D01*
Y-277293D01*
X86441Y-277188D01*
X86831Y-277005D01*
X87280Y-277190D01*
X87917D01*
X88505Y-276947D01*
X88955Y-276497D01*
X89198Y-275909D01*
Y-275272D01*
X88955Y-274684D01*
X88505Y-274234D01*
X87917Y-273991D01*
X87280D01*
X86831Y-274176D01*
X86441Y-273993D01*
X86331Y-273888D01*
Y-272920D01*
X81737D01*
X79964Y-271147D01*
Y-269208D01*
X80041Y-269131D01*
X81798D01*
X81916Y-269107D01*
X84461D01*
Y-267927D01*
X84961Y-267635D01*
X85312Y-267779D01*
X85948D01*
X86536Y-267536D01*
X86986Y-267086D01*
X87230Y-266498D01*
Y-265861D01*
X86986Y-265273D01*
X86693Y-264980D01*
X86986Y-264686D01*
X87230Y-264098D01*
Y-263461D01*
X86986Y-262873D01*
X86536Y-262423D01*
X86406Y-262369D01*
X86308Y-261879D01*
X86495Y-261692D01*
X86760Y-261295D01*
X86853Y-260827D01*
Y-260658D01*
X86972D01*
X87634Y-260384D01*
X88140Y-259878D01*
X88355Y-259358D01*
D02*
G37*
G36*
X2237Y-268299D02*
X2035D01*
Y-273130D01*
X6866D01*
Y-272928D01*
X6503Y-271572D01*
X5801Y-270357D01*
X4809Y-269364D01*
X3593Y-268663D01*
X2237Y-268299D01*
D02*
G37*
G36*
X-17763D02*
X-17965D01*
Y-273130D01*
X-13134D01*
Y-272928D01*
X-13497Y-271572D01*
X-14199Y-270357D01*
X-15191Y-269364D01*
X-16407Y-268663D01*
X-17763Y-268299D01*
D02*
G37*
G36*
X-18965D02*
X-19166D01*
X-20522Y-268663D01*
X-21738Y-269364D01*
X-22730Y-270357D01*
X-23432Y-271572D01*
X-23795Y-272928D01*
Y-273130D01*
X-18965D01*
Y-268299D01*
D02*
G37*
G36*
X1035D02*
X834D01*
X-522Y-268663D01*
X-1738Y-269364D01*
X-2730Y-270357D01*
X-3432Y-271572D01*
X-3795Y-272928D01*
Y-273130D01*
X1035D01*
Y-268299D01*
D02*
G37*
G36*
X22182Y-272100D02*
X20941D01*
Y-273341D01*
X21461Y-273126D01*
X21967Y-272620D01*
X22182Y-272100D01*
D02*
G37*
G36*
X11941D02*
X10700D01*
X10915Y-272620D01*
X11421Y-273126D01*
X11941Y-273341D01*
Y-272100D01*
D02*
G37*
G36*
X58182D02*
X56941D01*
Y-273341D01*
X57461Y-273126D01*
X57967Y-272620D01*
X58182Y-272100D01*
D02*
G37*
G36*
X51941D02*
X50700D01*
X50915Y-272620D01*
X51421Y-273126D01*
X51941Y-273341D01*
Y-272100D01*
D02*
G37*
G36*
X46033Y-273138D02*
X44791D01*
Y-274379D01*
X45311Y-274164D01*
X45817Y-273657D01*
X46033Y-273138D01*
D02*
G37*
G36*
X43791D02*
X42550D01*
X42765Y-273657D01*
X43272Y-274164D01*
X43791Y-274379D01*
Y-273138D01*
D02*
G37*
G36*
X17941Y-273859D02*
X17421Y-274074D01*
X16915Y-274580D01*
X16703Y-275092D01*
X16179D01*
X15967Y-274580D01*
X15461Y-274074D01*
X14941Y-273859D01*
Y-275600D01*
Y-277341D01*
X15461Y-277126D01*
X15967Y-276620D01*
X16179Y-276108D01*
X16703D01*
X16915Y-276620D01*
X17421Y-277126D01*
X17941Y-277341D01*
Y-275600D01*
Y-273859D01*
D02*
G37*
G36*
X13941D02*
X13421Y-274074D01*
X12915Y-274580D01*
X12703Y-275092D01*
X12179D01*
X11967Y-274580D01*
X11461Y-274074D01*
X10941Y-273859D01*
Y-275600D01*
Y-277341D01*
X11461Y-277126D01*
X11967Y-276620D01*
X12179Y-276108D01*
X12703D01*
X12915Y-276620D01*
X13421Y-277126D01*
X13941Y-277341D01*
Y-275600D01*
Y-273859D01*
D02*
G37*
G36*
X53941D02*
X53421Y-274074D01*
X52915Y-274580D01*
X52703Y-275092D01*
X52179D01*
X51967Y-274580D01*
X51461Y-274074D01*
X50941Y-273859D01*
Y-275600D01*
Y-277341D01*
X51461Y-277126D01*
X51967Y-276620D01*
X52179Y-276108D01*
X52703D01*
X52915Y-276620D01*
X53421Y-277126D01*
X53941Y-277341D01*
Y-275600D01*
Y-273859D01*
D02*
G37*
G36*
X54941D02*
Y-275100D01*
X56182D01*
X55967Y-274580D01*
X55461Y-274074D01*
X54941Y-273859D01*
D02*
G37*
G36*
X49941D02*
X49421Y-274074D01*
X48915Y-274580D01*
X48700Y-275100D01*
X49941D01*
Y-273859D01*
D02*
G37*
G36*
X34941D02*
Y-275100D01*
X36182D01*
X35967Y-274580D01*
X35461Y-274074D01*
X34941Y-273859D01*
D02*
G37*
G36*
X33941D02*
X33421Y-274074D01*
X32915Y-274580D01*
X32700Y-275100D01*
X33941D01*
Y-273859D01*
D02*
G37*
G36*
X18941D02*
Y-275100D01*
X20182D01*
X19967Y-274580D01*
X19461Y-274074D01*
X18941Y-273859D01*
D02*
G37*
G36*
X9941D02*
X9421Y-274074D01*
X8915Y-274580D01*
X8700Y-275100D01*
X9941D01*
Y-273859D01*
D02*
G37*
G36*
X-9059D02*
Y-275100D01*
X-7818D01*
X-8033Y-274580D01*
X-8539Y-274074D01*
X-9059Y-273859D01*
D02*
G37*
G36*
X-10059D02*
X-10579Y-274074D01*
X-11085Y-274580D01*
X-11300Y-275100D01*
X-10059D01*
Y-273859D01*
D02*
G37*
G36*
X36182Y-276100D02*
X34941D01*
Y-277341D01*
X35461Y-277126D01*
X35967Y-276620D01*
X36182Y-276100D01*
D02*
G37*
G36*
X33941D02*
X32700D01*
X32915Y-276620D01*
X33421Y-277126D01*
X33941Y-277341D01*
Y-276100D01*
D02*
G37*
G36*
X20182D02*
X18941D01*
Y-277341D01*
X19461Y-277126D01*
X19967Y-276620D01*
X20182Y-276100D01*
D02*
G37*
G36*
X9941D02*
X8700D01*
X8915Y-276620D01*
X9421Y-277126D01*
X9941Y-277341D01*
Y-276100D01*
D02*
G37*
G36*
X-7818D02*
X-9059D01*
Y-277341D01*
X-8539Y-277126D01*
X-8033Y-276620D01*
X-7818Y-276100D01*
D02*
G37*
G36*
X-10059D02*
X-11300D01*
X-11085Y-276620D01*
X-10579Y-277126D01*
X-10059Y-277341D01*
Y-276100D01*
D02*
G37*
G36*
X56182D02*
X54941D01*
Y-277341D01*
X55461Y-277126D01*
X55967Y-276620D01*
X56182Y-276100D01*
D02*
G37*
G36*
X49941D02*
X48700D01*
X48915Y-276620D01*
X49421Y-277126D01*
X49941Y-277341D01*
Y-276100D01*
D02*
G37*
G36*
X6866Y-274130D02*
X2035D01*
Y-278961D01*
X2237D01*
X3593Y-278597D01*
X4809Y-277896D01*
X5801Y-276903D01*
X6503Y-275688D01*
X6866Y-274332D01*
Y-274130D01*
D02*
G37*
G36*
X1035D02*
X-3795D01*
Y-274332D01*
X-3432Y-275688D01*
X-2730Y-276903D01*
X-1738Y-277896D01*
X-522Y-278597D01*
X834Y-278961D01*
X1035D01*
Y-274130D01*
D02*
G37*
G36*
X-13134D02*
X-17965D01*
Y-278961D01*
X-17763D01*
X-16407Y-278597D01*
X-15191Y-277896D01*
X-14199Y-276903D01*
X-13497Y-275688D01*
X-13134Y-274332D01*
Y-274130D01*
D02*
G37*
G36*
X-18965D02*
X-23795D01*
Y-274332D01*
X-23432Y-275688D01*
X-22730Y-276903D01*
X-21738Y-277896D01*
X-20522Y-278597D01*
X-19166Y-278961D01*
X-18965D01*
Y-274130D01*
D02*
G37*
G36*
X15941Y-277859D02*
X15421Y-278074D01*
X14915Y-278580D01*
X14703Y-279092D01*
X14179D01*
X13967Y-278580D01*
X13461Y-278074D01*
X12941Y-277859D01*
Y-279600D01*
Y-281341D01*
X13461Y-281126D01*
X13967Y-280620D01*
X14179Y-280108D01*
X14703D01*
X14915Y-280620D01*
X15421Y-281126D01*
X15941Y-281341D01*
Y-279600D01*
Y-277859D01*
D02*
G37*
G36*
X11941D02*
X11421Y-278074D01*
X10915Y-278580D01*
X10703Y-279092D01*
X10179D01*
X9967Y-278580D01*
X9461Y-278074D01*
X8941Y-277859D01*
Y-279600D01*
Y-281341D01*
X9461Y-281126D01*
X9967Y-280620D01*
X10179Y-280108D01*
X10703D01*
X10915Y-280620D01*
X11421Y-281126D01*
X11941Y-281341D01*
Y-279600D01*
Y-277859D01*
D02*
G37*
G36*
X-8059D02*
X-8579Y-278074D01*
X-9085Y-278580D01*
X-9297Y-279092D01*
X-9821D01*
X-10033Y-278580D01*
X-10539Y-278074D01*
X-11059Y-277859D01*
Y-279600D01*
Y-281341D01*
X-10539Y-281126D01*
X-10033Y-280620D01*
X-9821Y-280108D01*
X-9297D01*
X-9085Y-280620D01*
X-8579Y-281126D01*
X-8059Y-281341D01*
Y-279600D01*
Y-277859D01*
D02*
G37*
G36*
X55941D02*
X55421Y-278074D01*
X54915Y-278580D01*
X54703Y-279092D01*
X54179D01*
X53967Y-278580D01*
X53461Y-278074D01*
X52941Y-277859D01*
Y-279600D01*
Y-281341D01*
X53461Y-281126D01*
X53967Y-280620D01*
X54179Y-280108D01*
X54703D01*
X54915Y-280620D01*
X55421Y-281126D01*
X55941Y-281341D01*
Y-279600D01*
Y-277859D01*
D02*
G37*
G36*
X51941D02*
X51421Y-278074D01*
X50915Y-278580D01*
X50703Y-279092D01*
X50179D01*
X49967Y-278580D01*
X49461Y-278074D01*
X48941Y-277859D01*
Y-279600D01*
Y-281341D01*
X49461Y-281126D01*
X49967Y-280620D01*
X50179Y-280108D01*
X50703D01*
X50915Y-280620D01*
X51421Y-281126D01*
X51941Y-281341D01*
Y-279600D01*
Y-277859D01*
D02*
G37*
G36*
X47941D02*
X47421Y-278074D01*
X46915Y-278580D01*
X46703Y-279092D01*
X46179D01*
X45967Y-278580D01*
X45461Y-278074D01*
X44941Y-277859D01*
Y-279600D01*
Y-281341D01*
X45461Y-281126D01*
X45967Y-280620D01*
X46179Y-280108D01*
X46703D01*
X46915Y-280620D01*
X47421Y-281126D01*
X47941Y-281341D01*
Y-279600D01*
Y-277859D01*
D02*
G37*
G36*
X56941D02*
Y-279100D01*
X58182D01*
X57967Y-278580D01*
X57461Y-278074D01*
X56941Y-277859D01*
D02*
G37*
G36*
X43941D02*
X43421Y-278074D01*
X42915Y-278580D01*
X42700Y-279100D01*
X43941D01*
Y-277859D01*
D02*
G37*
G36*
X16941D02*
Y-279100D01*
X18182D01*
X17967Y-278580D01*
X17461Y-278074D01*
X16941Y-277859D01*
D02*
G37*
G36*
X7941D02*
X7421Y-278074D01*
X6915Y-278580D01*
X6700Y-279100D01*
X7941D01*
Y-277859D01*
D02*
G37*
G36*
X-7059D02*
Y-279100D01*
X-5818D01*
X-6033Y-278580D01*
X-6539Y-278074D01*
X-7059Y-277859D01*
D02*
G37*
G36*
X-12059D02*
X-12579Y-278074D01*
X-13085Y-278580D01*
X-13300Y-279100D01*
X-12059D01*
Y-277859D01*
D02*
G37*
G36*
X18182Y-280100D02*
X16941D01*
Y-281341D01*
X17461Y-281126D01*
X17967Y-280620D01*
X18182Y-280100D01*
D02*
G37*
G36*
X7941D02*
X6700D01*
X6915Y-280620D01*
X7421Y-281126D01*
X7941Y-281341D01*
Y-280100D01*
D02*
G37*
G36*
X-5818D02*
X-7059D01*
Y-281341D01*
X-6539Y-281126D01*
X-6033Y-280620D01*
X-5818Y-280100D01*
D02*
G37*
G36*
X-12059D02*
X-13300D01*
X-13085Y-280620D01*
X-12579Y-281126D01*
X-12059Y-281341D01*
Y-280100D01*
D02*
G37*
G36*
X58182D02*
X56941D01*
Y-281341D01*
X57461Y-281126D01*
X57967Y-280620D01*
X58182Y-280100D01*
D02*
G37*
G36*
X43941D02*
X42700D01*
X42915Y-280620D01*
X43421Y-281126D01*
X43941Y-281341D01*
Y-280100D01*
D02*
G37*
G36*
X22941Y-281859D02*
Y-283100D01*
X24182D01*
X23967Y-282580D01*
X23461Y-282074D01*
X22941Y-281859D01*
D02*
G37*
G36*
X21941D02*
X21421Y-282074D01*
X20915Y-282580D01*
X20700Y-283100D01*
X21941D01*
Y-281859D01*
D02*
G37*
G36*
X72063Y-281799D02*
X65732D01*
Y-284366D01*
X66850D01*
X67184Y-284866D01*
X67156Y-284933D01*
X70639D01*
X70611Y-284866D01*
X70945Y-284366D01*
X72063D01*
Y-281799D01*
D02*
G37*
G36*
X24182Y-284100D02*
X22941D01*
Y-285341D01*
X23461Y-285126D01*
X23967Y-284620D01*
X24182Y-284100D01*
D02*
G37*
G36*
X21941D02*
X20700D01*
X20915Y-284620D01*
X21421Y-285126D01*
X21941Y-285341D01*
Y-284100D01*
D02*
G37*
G36*
X-23304Y-280880D02*
X-23940D01*
X-24528Y-281124D01*
X-24979Y-281574D01*
X-25222Y-282162D01*
Y-282799D01*
X-24979Y-283387D01*
X-24528Y-283837D01*
X-23940Y-284080D01*
X-23304D01*
X-22764Y-283857D01*
X-20977D01*
Y-284830D01*
X-21568D01*
Y-285347D01*
X-22430D01*
X-22716Y-285061D01*
X-23304Y-284817D01*
X-23940D01*
X-24528Y-285061D01*
X-24979Y-285511D01*
X-25222Y-286099D01*
Y-286736D01*
X-24979Y-287324D01*
X-24528Y-287774D01*
X-23940Y-288017D01*
X-23304D01*
X-22764Y-287794D01*
X-21568D01*
Y-289131D01*
X-22583D01*
X-22716Y-288998D01*
X-23304Y-288754D01*
X-23940D01*
X-24528Y-288998D01*
X-24979Y-289448D01*
X-25222Y-290036D01*
Y-290673D01*
X-24979Y-291261D01*
X-24528Y-291711D01*
X-23940Y-291954D01*
X-23304D01*
X-22716Y-291711D01*
X-22583Y-291578D01*
X-21568D01*
Y-292335D01*
X-20977D01*
Y-292867D01*
X-22879D01*
X-23304Y-292691D01*
X-23940D01*
X-24528Y-292935D01*
X-24979Y-293385D01*
X-25222Y-293973D01*
Y-294610D01*
X-24979Y-295198D01*
X-24528Y-295648D01*
X-23940Y-295891D01*
X-23304D01*
X-22716Y-295648D01*
X-22586Y-295518D01*
X-20977D01*
Y-296076D01*
X-15834D01*
Y-292113D01*
X-17802D01*
Y-288792D01*
Y-285052D01*
X-15834D01*
Y-281090D01*
X-20977D01*
Y-281410D01*
X-22430D01*
X-22716Y-281124D01*
X-23304Y-280880D01*
D02*
G37*
G36*
X33477Y-279515D02*
X27940D01*
Y-281745D01*
X27131D01*
X26624Y-281846D01*
X26596Y-281865D01*
X26256D01*
X25668Y-282108D01*
X25218Y-282558D01*
X24975Y-283146D01*
Y-283783D01*
X25218Y-284371D01*
X25668Y-284821D01*
X26256Y-285065D01*
X26893D01*
X27440Y-284838D01*
X27651Y-284913D01*
X27940Y-285069D01*
Y-286627D01*
X33477D01*
Y-279515D01*
D02*
G37*
G36*
X23941Y-285859D02*
X23421Y-286074D01*
X22915Y-286580D01*
X22703Y-287092D01*
X22179D01*
X21967Y-286580D01*
X21461Y-286074D01*
X20941Y-285859D01*
Y-287600D01*
Y-289341D01*
X21461Y-289126D01*
X21967Y-288620D01*
X22179Y-288108D01*
X22703D01*
X22915Y-288620D01*
X23421Y-289126D01*
X23941Y-289341D01*
Y-287600D01*
Y-285859D01*
D02*
G37*
G36*
X55941D02*
X55421Y-286074D01*
X54915Y-286580D01*
X54703Y-287092D01*
X54179D01*
X53967Y-286580D01*
X53461Y-286074D01*
X52941Y-285859D01*
Y-287600D01*
Y-289341D01*
X53461Y-289126D01*
X53967Y-288620D01*
X54179Y-288108D01*
X54703D01*
X54915Y-288620D01*
X55421Y-289126D01*
X55941Y-289341D01*
Y-287600D01*
Y-285859D01*
D02*
G37*
G36*
X51941D02*
X51421Y-286074D01*
X50915Y-286580D01*
X50703Y-287092D01*
X50179D01*
X49967Y-286580D01*
X49461Y-286074D01*
X48941Y-285859D01*
Y-287600D01*
Y-289341D01*
X49461Y-289126D01*
X49967Y-288620D01*
X50179Y-288108D01*
X50703D01*
X50915Y-288620D01*
X51421Y-289126D01*
X51941Y-289341D01*
Y-287600D01*
Y-285859D01*
D02*
G37*
G36*
X47941D02*
X47421Y-286074D01*
X46915Y-286580D01*
X46703Y-287092D01*
X46179D01*
X45967Y-286580D01*
X45461Y-286074D01*
X44941Y-285859D01*
Y-287600D01*
Y-289341D01*
X45461Y-289126D01*
X45967Y-288620D01*
X46179Y-288108D01*
X46703D01*
X46915Y-288620D01*
X47421Y-289126D01*
X47941Y-289341D01*
Y-287600D01*
Y-285859D01*
D02*
G37*
G36*
X56941D02*
Y-287100D01*
X58182D01*
X57967Y-286580D01*
X57461Y-286074D01*
X56941Y-285859D01*
D02*
G37*
G36*
X43941D02*
X43421Y-286074D01*
X42915Y-286580D01*
X42700Y-287100D01*
X43941D01*
Y-285859D01*
D02*
G37*
G36*
X24941D02*
Y-287100D01*
X26182D01*
X25967Y-286580D01*
X25461Y-286074D01*
X24941Y-285859D01*
D02*
G37*
G36*
X19941D02*
X19421Y-286074D01*
X18915Y-286580D01*
X18700Y-287100D01*
X19941D01*
Y-285859D01*
D02*
G37*
G36*
X70639Y-285933D02*
X69398D01*
Y-287174D01*
X69917Y-286959D01*
X70424Y-286453D01*
X70639Y-285933D01*
D02*
G37*
G36*
X68398D02*
X67156D01*
X67372Y-286453D01*
X67878Y-286959D01*
X68398Y-287174D01*
Y-285933D01*
D02*
G37*
G36*
X58182Y-288100D02*
X56941D01*
Y-289341D01*
X57461Y-289126D01*
X57967Y-288620D01*
X58182Y-288100D01*
D02*
G37*
G36*
X43941D02*
X42700D01*
X42915Y-288620D01*
X43421Y-289126D01*
X43941Y-289341D01*
Y-288100D01*
D02*
G37*
G36*
X26182D02*
X24941D01*
Y-289341D01*
X25461Y-289126D01*
X25967Y-288620D01*
X26182Y-288100D01*
D02*
G37*
G36*
X19941D02*
X18700D01*
X18915Y-288620D01*
X19421Y-289126D01*
X19941Y-289341D01*
Y-288100D01*
D02*
G37*
G36*
X30996Y-287976D02*
X27740D01*
Y-289332D01*
X27240Y-289666D01*
X27075Y-289597D01*
Y-291339D01*
Y-293080D01*
X27240Y-293011D01*
X27740Y-293243D01*
Y-295488D01*
X30996D01*
Y-291732D01*
Y-287976D01*
D02*
G37*
G36*
X26075Y-289597D02*
X25555Y-289813D01*
X25049Y-290319D01*
X24834Y-290839D01*
X26075D01*
Y-289597D01*
D02*
G37*
G36*
X21941Y-289859D02*
X21421Y-290074D01*
X20915Y-290580D01*
X20703Y-291092D01*
X20179D01*
X19967Y-290580D01*
X19461Y-290074D01*
X18941Y-289859D01*
Y-291600D01*
Y-293341D01*
X19461Y-293126D01*
X19967Y-292620D01*
X20179Y-292108D01*
X20703D01*
X20915Y-292620D01*
X21421Y-293126D01*
X21941Y-293341D01*
Y-291600D01*
Y-289859D01*
D02*
G37*
G36*
X17941D02*
X17421Y-290074D01*
X16915Y-290580D01*
X16703Y-291092D01*
X16179D01*
X15967Y-290580D01*
X15461Y-290074D01*
X14941Y-289859D01*
Y-291600D01*
Y-293341D01*
X15461Y-293126D01*
X15967Y-292620D01*
X16179Y-292108D01*
X16703D01*
X16915Y-292620D01*
X17421Y-293126D01*
X17941Y-293341D01*
Y-291600D01*
Y-289859D01*
D02*
G37*
G36*
X53941D02*
X53421Y-290074D01*
X52915Y-290580D01*
X52703Y-291092D01*
X52179D01*
X51967Y-290580D01*
X51461Y-290074D01*
X50941Y-289859D01*
Y-291600D01*
Y-293341D01*
X51461Y-293126D01*
X51967Y-292620D01*
X52179Y-292108D01*
X52703D01*
X52915Y-292620D01*
X53421Y-293126D01*
X53941Y-293341D01*
Y-291600D01*
Y-289859D01*
D02*
G37*
G36*
X49941D02*
X49421Y-290074D01*
X48915Y-290580D01*
X48703Y-291092D01*
X48179D01*
X47967Y-290580D01*
X47461Y-290074D01*
X46941Y-289859D01*
Y-291600D01*
Y-293341D01*
X47461Y-293126D01*
X47967Y-292620D01*
X48179Y-292108D01*
X48703D01*
X48915Y-292620D01*
X49421Y-293126D01*
X49941Y-293341D01*
Y-291600D01*
Y-289859D01*
D02*
G37*
G36*
X54941D02*
Y-291100D01*
X56182D01*
X55967Y-290580D01*
X55461Y-290074D01*
X54941Y-289859D01*
D02*
G37*
G36*
X45941D02*
X45421Y-290074D01*
X44915Y-290580D01*
X44700Y-291100D01*
X45941D01*
Y-289859D01*
D02*
G37*
G36*
X22941D02*
Y-291100D01*
X24182D01*
X23967Y-290580D01*
X23461Y-290074D01*
X22941Y-289859D01*
D02*
G37*
G36*
X13941D02*
X13421Y-290074D01*
X12915Y-290580D01*
X12700Y-291100D01*
X13941D01*
Y-289859D01*
D02*
G37*
G36*
X26075Y-291839D02*
X24834D01*
X25049Y-292358D01*
X25555Y-292864D01*
X26075Y-293080D01*
Y-291839D01*
D02*
G37*
G36*
X56182Y-292100D02*
X54941D01*
Y-293341D01*
X55461Y-293126D01*
X55967Y-292620D01*
X56182Y-292100D01*
D02*
G37*
G36*
X45941D02*
X44700D01*
X44915Y-292620D01*
X45421Y-293126D01*
X45941Y-293341D01*
Y-292100D01*
D02*
G37*
G36*
X24182D02*
X22941D01*
Y-293341D01*
X23461Y-293126D01*
X23967Y-292620D01*
X24182Y-292100D01*
D02*
G37*
G36*
X13941D02*
X12700D01*
X12915Y-292620D01*
X13421Y-293126D01*
X13941Y-293341D01*
Y-292100D01*
D02*
G37*
G36*
X25941Y-297859D02*
X25421Y-298074D01*
X24915Y-298580D01*
X24703Y-299092D01*
X24179D01*
X23967Y-298580D01*
X23461Y-298074D01*
X22941Y-297859D01*
Y-299600D01*
Y-301341D01*
X23461Y-301126D01*
X23967Y-300620D01*
X24179Y-300108D01*
X24703D01*
X24915Y-300620D01*
X25421Y-301126D01*
X25941Y-301341D01*
Y-299600D01*
Y-297859D01*
D02*
G37*
G36*
X21941D02*
X21421Y-298074D01*
X20915Y-298580D01*
X20703Y-299092D01*
X20179D01*
X19967Y-298580D01*
X19461Y-298074D01*
X18941Y-297859D01*
Y-299600D01*
Y-301341D01*
X19461Y-301126D01*
X19967Y-300620D01*
X20179Y-300108D01*
X20703D01*
X20915Y-300620D01*
X21421Y-301126D01*
X21941Y-301341D01*
Y-299600D01*
Y-297859D01*
D02*
G37*
G36*
X17941D02*
X17421Y-298074D01*
X16915Y-298580D01*
X16703Y-299092D01*
X16179D01*
X15967Y-298580D01*
X15461Y-298074D01*
X14941Y-297859D01*
Y-299600D01*
Y-301341D01*
X15461Y-301126D01*
X15967Y-300620D01*
X16179Y-300108D01*
X16703D01*
X16915Y-300620D01*
X17421Y-301126D01*
X17941Y-301341D01*
Y-299600D01*
Y-297859D01*
D02*
G37*
G36*
X13941D02*
X13421Y-298074D01*
X12915Y-298580D01*
X12703Y-299092D01*
X12179D01*
X11967Y-298580D01*
X11461Y-298074D01*
X10941Y-297859D01*
Y-299600D01*
Y-301341D01*
X11461Y-301126D01*
X11967Y-300620D01*
X12179Y-300108D01*
X12703D01*
X12915Y-300620D01*
X13421Y-301126D01*
X13941Y-301341D01*
Y-299600D01*
Y-297859D01*
D02*
G37*
G36*
X-6059D02*
X-6579Y-298074D01*
X-7085Y-298580D01*
X-7297Y-299092D01*
X-7821D01*
X-8033Y-298580D01*
X-8539Y-298074D01*
X-9059Y-297859D01*
Y-299600D01*
Y-301341D01*
X-8539Y-301126D01*
X-8033Y-300620D01*
X-7821Y-300108D01*
X-7297D01*
X-7085Y-300620D01*
X-6579Y-301126D01*
X-6059Y-301341D01*
Y-299600D01*
Y-297859D01*
D02*
G37*
G36*
X53941D02*
X53421Y-298074D01*
X52915Y-298580D01*
X52703Y-299092D01*
X52179D01*
X51967Y-298580D01*
X51461Y-298074D01*
X50941Y-297859D01*
Y-299600D01*
Y-301341D01*
X51461Y-301126D01*
X51967Y-300620D01*
X52179Y-300108D01*
X52703D01*
X52915Y-300620D01*
X53421Y-301126D01*
X53941Y-301341D01*
Y-299600D01*
Y-297859D01*
D02*
G37*
G36*
X49941D02*
X49421Y-298074D01*
X48915Y-298580D01*
X48703Y-299092D01*
X48179D01*
X47967Y-298580D01*
X47461Y-298074D01*
X46941Y-297859D01*
Y-299600D01*
Y-301341D01*
X47461Y-301126D01*
X47967Y-300620D01*
X48179Y-300108D01*
X48703D01*
X48915Y-300620D01*
X49421Y-301126D01*
X49941Y-301341D01*
Y-299600D01*
Y-297859D01*
D02*
G37*
G36*
X45941D02*
X45421Y-298074D01*
X44915Y-298580D01*
X44703Y-299092D01*
X44179D01*
X43967Y-298580D01*
X43461Y-298074D01*
X42941Y-297859D01*
Y-299600D01*
Y-301341D01*
X43461Y-301126D01*
X43967Y-300620D01*
X44179Y-300108D01*
X44703D01*
X44915Y-300620D01*
X45421Y-301126D01*
X45941Y-301341D01*
Y-299600D01*
Y-297859D01*
D02*
G37*
G36*
X54941D02*
Y-299100D01*
X56182D01*
X55967Y-298580D01*
X55461Y-298074D01*
X54941Y-297859D01*
D02*
G37*
G36*
X41941D02*
X41421Y-298074D01*
X40915Y-298580D01*
X40700Y-299100D01*
X41941D01*
Y-297859D01*
D02*
G37*
G36*
X34941D02*
Y-299100D01*
X36182D01*
X35967Y-298580D01*
X35461Y-298074D01*
X34941Y-297859D01*
D02*
G37*
G36*
X33941D02*
X33421Y-298074D01*
X32915Y-298580D01*
X32700Y-299100D01*
X33941D01*
Y-297859D01*
D02*
G37*
G36*
X26941D02*
Y-299100D01*
X28182D01*
X27967Y-298580D01*
X27461Y-298074D01*
X26941Y-297859D01*
D02*
G37*
G36*
X9941D02*
X9421Y-298074D01*
X8915Y-298580D01*
X8700Y-299100D01*
X9941D01*
Y-297859D01*
D02*
G37*
G36*
X-5059D02*
Y-299100D01*
X-3818D01*
X-4033Y-298580D01*
X-4539Y-298074D01*
X-5059Y-297859D01*
D02*
G37*
G36*
X-10059D02*
X-10579Y-298074D01*
X-11085Y-298580D01*
X-11300Y-299100D01*
X-10059D01*
Y-297859D01*
D02*
G37*
G36*
X-25059D02*
Y-299100D01*
X-23818D01*
X-24033Y-298580D01*
X-24539Y-298074D01*
X-25059Y-297859D01*
D02*
G37*
G36*
X41941Y-300100D02*
X40700D01*
X40915Y-300620D01*
X41421Y-301126D01*
X41941Y-301341D01*
Y-300100D01*
D02*
G37*
G36*
X36182D02*
X34941D01*
Y-301341D01*
X35461Y-301126D01*
X35967Y-300620D01*
X36182Y-300100D01*
D02*
G37*
G36*
X33941D02*
X32700D01*
X32915Y-300620D01*
X33421Y-301126D01*
X33941Y-301341D01*
Y-300100D01*
D02*
G37*
G36*
X28182D02*
X26941D01*
Y-301341D01*
X27461Y-301126D01*
X27967Y-300620D01*
X28182Y-300100D01*
D02*
G37*
G36*
X9941D02*
X8700D01*
X8915Y-300620D01*
X9421Y-301126D01*
X9941Y-301341D01*
Y-300100D01*
D02*
G37*
G36*
X-3818D02*
X-5059D01*
Y-301341D01*
X-4539Y-301126D01*
X-4033Y-300620D01*
X-3818Y-300100D01*
D02*
G37*
G36*
X-10059D02*
X-11300D01*
X-11085Y-300620D01*
X-10579Y-301126D01*
X-10059Y-301341D01*
Y-300100D01*
D02*
G37*
G36*
X-23818D02*
X-25059D01*
Y-301341D01*
X-24539Y-301126D01*
X-24033Y-300620D01*
X-23818Y-300100D01*
D02*
G37*
G36*
X56182D02*
X54941D01*
Y-301341D01*
X55461Y-301126D01*
X55967Y-300620D01*
X56182Y-300100D01*
D02*
G37*
G36*
X23941Y-301859D02*
X23421Y-302074D01*
X22915Y-302580D01*
X22703Y-303092D01*
X22179D01*
X21967Y-302580D01*
X21461Y-302074D01*
X20941Y-301859D01*
Y-303600D01*
Y-305341D01*
X21461Y-305126D01*
X21967Y-304620D01*
X22179Y-304108D01*
X22703D01*
X22915Y-304620D01*
X23421Y-305126D01*
X23941Y-305341D01*
Y-303600D01*
Y-301859D01*
D02*
G37*
G36*
X19941D02*
X19421Y-302074D01*
X18915Y-302580D01*
X18703Y-303092D01*
X18179D01*
X17967Y-302580D01*
X17461Y-302074D01*
X16941Y-301859D01*
Y-303600D01*
Y-305341D01*
X17461Y-305126D01*
X17967Y-304620D01*
X18179Y-304108D01*
X18703D01*
X18915Y-304620D01*
X19421Y-305126D01*
X19941Y-305341D01*
Y-303600D01*
Y-301859D01*
D02*
G37*
G36*
X15941D02*
X15421Y-302074D01*
X14915Y-302580D01*
X14703Y-303092D01*
X14179D01*
X13967Y-302580D01*
X13461Y-302074D01*
X12941Y-301859D01*
Y-303600D01*
Y-305341D01*
X13461Y-305126D01*
X13967Y-304620D01*
X14179Y-304108D01*
X14703D01*
X14915Y-304620D01*
X15421Y-305126D01*
X15941Y-305341D01*
Y-303600D01*
Y-301859D01*
D02*
G37*
G36*
X55941D02*
X55421Y-302074D01*
X54915Y-302580D01*
X54703Y-303092D01*
X54179D01*
X53967Y-302580D01*
X53461Y-302074D01*
X52941Y-301859D01*
Y-303600D01*
Y-305341D01*
X53461Y-305126D01*
X53967Y-304620D01*
X54179Y-304108D01*
X54703D01*
X54915Y-304620D01*
X55421Y-305126D01*
X55941Y-305341D01*
Y-303600D01*
Y-301859D01*
D02*
G37*
G36*
X51941D02*
X51421Y-302074D01*
X50915Y-302580D01*
X50703Y-303092D01*
X50179D01*
X49967Y-302580D01*
X49461Y-302074D01*
X48941Y-301859D01*
Y-303600D01*
Y-305341D01*
X49461Y-305126D01*
X49967Y-304620D01*
X50179Y-304108D01*
X50703D01*
X50915Y-304620D01*
X51421Y-305126D01*
X51941Y-305341D01*
Y-303600D01*
Y-301859D01*
D02*
G37*
G36*
X56941D02*
Y-303100D01*
X58182D01*
X57967Y-302580D01*
X57461Y-302074D01*
X56941Y-301859D01*
D02*
G37*
G36*
X47941D02*
X47421Y-302074D01*
X46915Y-302580D01*
X46700Y-303100D01*
X47941D01*
Y-301859D01*
D02*
G37*
G36*
X24941D02*
Y-303100D01*
X26182D01*
X25967Y-302580D01*
X25461Y-302074D01*
X24941Y-301859D01*
D02*
G37*
G36*
X11941D02*
X11421Y-302074D01*
X10915Y-302580D01*
X10700Y-303100D01*
X11941D01*
Y-301859D01*
D02*
G37*
G36*
X-7059D02*
Y-303100D01*
X-5818D01*
X-6033Y-302580D01*
X-6539Y-302074D01*
X-7059Y-301859D01*
D02*
G37*
G36*
X-8059D02*
X-8579Y-302074D01*
X-9085Y-302580D01*
X-9300Y-303100D01*
X-8059D01*
Y-301859D01*
D02*
G37*
G36*
X26182Y-304100D02*
X24941D01*
Y-305341D01*
X25461Y-305126D01*
X25967Y-304620D01*
X26182Y-304100D01*
D02*
G37*
G36*
X11941D02*
X10700D01*
X10915Y-304620D01*
X11421Y-305126D01*
X11941Y-305341D01*
Y-304100D01*
D02*
G37*
G36*
X-5818D02*
X-7059D01*
Y-305341D01*
X-6539Y-305126D01*
X-6033Y-304620D01*
X-5818Y-304100D01*
D02*
G37*
G36*
X-8059D02*
X-9300D01*
X-9085Y-304620D01*
X-8579Y-305126D01*
X-8059Y-305341D01*
Y-304100D01*
D02*
G37*
G36*
X58182D02*
X56941D01*
Y-305341D01*
X57461Y-305126D01*
X57967Y-304620D01*
X58182Y-304100D01*
D02*
G37*
G36*
X47941D02*
X46700D01*
X46915Y-304620D01*
X47421Y-305126D01*
X47941Y-305341D01*
Y-304100D01*
D02*
G37*
G36*
X-17763Y-301450D02*
X-17965D01*
Y-306281D01*
X-13134D01*
Y-306079D01*
X-13497Y-304724D01*
X-14199Y-303508D01*
X-15191Y-302516D01*
X-16407Y-301814D01*
X-17763Y-301450D01*
D02*
G37*
G36*
X2237D02*
X2035D01*
Y-306281D01*
X6866D01*
Y-306079D01*
X6503Y-304724D01*
X5801Y-303508D01*
X4809Y-302516D01*
X3593Y-301814D01*
X2237Y-301450D01*
D02*
G37*
G36*
X1035D02*
X834D01*
X-522Y-301814D01*
X-1738Y-302516D01*
X-2730Y-303508D01*
X-3432Y-304724D01*
X-3795Y-306079D01*
Y-306281D01*
X1035D01*
Y-301450D01*
D02*
G37*
G36*
X-18965D02*
X-19166D01*
X-20522Y-301814D01*
X-21738Y-302516D01*
X-22730Y-303508D01*
X-23432Y-304724D01*
X-23795Y-306079D01*
Y-306281D01*
X-18965D01*
Y-301450D01*
D02*
G37*
G36*
X44791Y-305345D02*
Y-306587D01*
X46033D01*
X45817Y-306067D01*
X45311Y-305561D01*
X44791Y-305345D01*
D02*
G37*
G36*
X43791D02*
X43272Y-305561D01*
X42765Y-306067D01*
X42550Y-306587D01*
X43791D01*
Y-305345D01*
D02*
G37*
G36*
X25941Y-305859D02*
X25421Y-306074D01*
X24915Y-306580D01*
X24703Y-307092D01*
X24179D01*
X23967Y-306580D01*
X23461Y-306074D01*
X22941Y-305859D01*
Y-307600D01*
Y-309341D01*
X23461Y-309126D01*
X23967Y-308620D01*
X24179Y-308108D01*
X24703D01*
X24915Y-308620D01*
X25421Y-309126D01*
X25941Y-309341D01*
Y-307600D01*
Y-305859D01*
D02*
G37*
G36*
X21941D02*
X21421Y-306074D01*
X20915Y-306580D01*
X20703Y-307092D01*
X20179D01*
X19967Y-306580D01*
X19461Y-306074D01*
X18941Y-305859D01*
Y-307600D01*
Y-309341D01*
X19461Y-309126D01*
X19967Y-308620D01*
X20179Y-308108D01*
X20703D01*
X20915Y-308620D01*
X21421Y-309126D01*
X21941Y-309341D01*
Y-307600D01*
Y-305859D01*
D02*
G37*
G36*
X17941D02*
X17421Y-306074D01*
X16915Y-306580D01*
X16703Y-307092D01*
X16179D01*
X15967Y-306580D01*
X15461Y-306074D01*
X14941Y-305859D01*
Y-307600D01*
Y-309341D01*
X15461Y-309126D01*
X15967Y-308620D01*
X16179Y-308108D01*
X16703D01*
X16915Y-308620D01*
X17421Y-309126D01*
X17941Y-309341D01*
Y-307600D01*
Y-305859D01*
D02*
G37*
G36*
X54941D02*
Y-307100D01*
X56182D01*
X55967Y-306580D01*
X55461Y-306074D01*
X54941Y-305859D01*
D02*
G37*
G36*
X53941D02*
X53421Y-306074D01*
X52915Y-306580D01*
X52700Y-307100D01*
X53941D01*
Y-305859D01*
D02*
G37*
G36*
X34941D02*
Y-307100D01*
X36182D01*
X35967Y-306580D01*
X35461Y-306074D01*
X34941Y-305859D01*
D02*
G37*
G36*
X33941D02*
X33421Y-306074D01*
X32915Y-306580D01*
X32700Y-307100D01*
X33941D01*
Y-305859D01*
D02*
G37*
G36*
X26941D02*
Y-307100D01*
X28182D01*
X27967Y-306580D01*
X27461Y-306074D01*
X26941Y-305859D01*
D02*
G37*
G36*
X13941D02*
X13421Y-306074D01*
X12915Y-306580D01*
X12700Y-307100D01*
X13941D01*
Y-305859D01*
D02*
G37*
G36*
X36182Y-308100D02*
X34941D01*
Y-309341D01*
X35461Y-309126D01*
X35967Y-308620D01*
X36182Y-308100D01*
D02*
G37*
G36*
X33941D02*
X32700D01*
X32915Y-308620D01*
X33421Y-309126D01*
X33941Y-309341D01*
Y-308100D01*
D02*
G37*
G36*
X28182D02*
X26941D01*
Y-309341D01*
X27461Y-309126D01*
X27967Y-308620D01*
X28182Y-308100D01*
D02*
G37*
G36*
X13941D02*
X12700D01*
X12915Y-308620D01*
X13421Y-309126D01*
X13941Y-309341D01*
Y-308100D01*
D02*
G37*
G36*
X56182D02*
X54941D01*
Y-309341D01*
X55461Y-309126D01*
X55967Y-308620D01*
X56182Y-308100D01*
D02*
G37*
G36*
X53941D02*
X52700D01*
X52915Y-308620D01*
X53421Y-309126D01*
X53941Y-309341D01*
Y-308100D01*
D02*
G37*
G36*
X23941Y-309859D02*
X23421Y-310074D01*
X22915Y-310580D01*
X22703Y-311092D01*
X22179D01*
X21967Y-310580D01*
X21461Y-310074D01*
X20941Y-309859D01*
Y-311600D01*
Y-313341D01*
X21461Y-313126D01*
X21967Y-312620D01*
X22179Y-312108D01*
X22703D01*
X22915Y-312620D01*
X23421Y-313126D01*
X23941Y-313341D01*
Y-311600D01*
Y-309859D01*
D02*
G37*
G36*
X19941D02*
X19421Y-310074D01*
X18915Y-310580D01*
X18703Y-311092D01*
X18179D01*
X17967Y-310580D01*
X17461Y-310074D01*
X16941Y-309859D01*
Y-311600D01*
Y-313341D01*
X17461Y-313126D01*
X17967Y-312620D01*
X18179Y-312108D01*
X18703D01*
X18915Y-312620D01*
X19421Y-313126D01*
X19941Y-313341D01*
Y-311600D01*
Y-309859D01*
D02*
G37*
G36*
X15941D02*
X15421Y-310074D01*
X14915Y-310580D01*
X14703Y-311092D01*
X14179D01*
X13967Y-310580D01*
X13461Y-310074D01*
X12941Y-309859D01*
Y-311600D01*
Y-313341D01*
X13461Y-313126D01*
X13967Y-312620D01*
X14179Y-312108D01*
X14703D01*
X14915Y-312620D01*
X15421Y-313126D01*
X15941Y-313341D01*
Y-311600D01*
Y-309859D01*
D02*
G37*
G36*
X55941D02*
X55421Y-310074D01*
X54915Y-310580D01*
X54703Y-311092D01*
X54179D01*
X53967Y-310580D01*
X53461Y-310074D01*
X52941Y-309859D01*
Y-311600D01*
Y-313341D01*
X53461Y-313126D01*
X53967Y-312620D01*
X54179Y-312108D01*
X54703D01*
X54915Y-312620D01*
X55421Y-313126D01*
X55941Y-313341D01*
Y-311600D01*
Y-309859D01*
D02*
G37*
G36*
X56941D02*
Y-311100D01*
X58182D01*
X57967Y-310580D01*
X57461Y-310074D01*
X56941Y-309859D01*
D02*
G37*
G36*
X51941D02*
X51421Y-310074D01*
X50915Y-310580D01*
X50700Y-311100D01*
X51941D01*
Y-309859D01*
D02*
G37*
G36*
X24941D02*
Y-311100D01*
X26182D01*
X25967Y-310580D01*
X25461Y-310074D01*
X24941Y-309859D01*
D02*
G37*
G36*
X11941D02*
X11421Y-310074D01*
X10915Y-310580D01*
X10700Y-311100D01*
X11941D01*
Y-309859D01*
D02*
G37*
G36*
X6866Y-307281D02*
X2035D01*
Y-312112D01*
X2237D01*
X3593Y-311749D01*
X4809Y-311047D01*
X5801Y-310054D01*
X6503Y-308839D01*
X6866Y-307483D01*
Y-307281D01*
D02*
G37*
G36*
X1035D02*
X-3795D01*
Y-307483D01*
X-3432Y-308839D01*
X-2730Y-310054D01*
X-1738Y-311047D01*
X-522Y-311749D01*
X834Y-312112D01*
X1035D01*
Y-307281D01*
D02*
G37*
G36*
X-13134D02*
X-17965D01*
Y-312112D01*
X-17763D01*
X-16407Y-311749D01*
X-15191Y-311047D01*
X-14199Y-310054D01*
X-13497Y-308839D01*
X-13134Y-307483D01*
Y-307281D01*
D02*
G37*
G36*
X-18965D02*
X-23795D01*
Y-307483D01*
X-23432Y-308839D01*
X-22730Y-310054D01*
X-21738Y-311047D01*
X-20522Y-311749D01*
X-19166Y-312112D01*
X-18965D01*
Y-307281D01*
D02*
G37*
G36*
X26182Y-312100D02*
X24941D01*
Y-313341D01*
X25461Y-313126D01*
X25967Y-312620D01*
X26182Y-312100D01*
D02*
G37*
G36*
X11941D02*
X10700D01*
X10915Y-312620D01*
X11421Y-313126D01*
X11941Y-313341D01*
Y-312100D01*
D02*
G37*
G36*
X58182D02*
X56941D01*
Y-313341D01*
X57461Y-313126D01*
X57967Y-312620D01*
X58182Y-312100D01*
D02*
G37*
G36*
X51941D02*
X50700D01*
X50915Y-312620D01*
X51421Y-313126D01*
X51941Y-313341D01*
Y-312100D01*
D02*
G37*
G36*
X86130Y-312235D02*
Y-313476D01*
X87371D01*
X87156Y-312957D01*
X86650Y-312450D01*
X86130Y-312235D01*
D02*
G37*
G36*
X49622Y-311622D02*
X44791D01*
Y-314189D01*
X49622D01*
Y-311622D01*
D02*
G37*
G36*
X-22059Y-313859D02*
X-22579Y-314074D01*
X-23085Y-314580D01*
X-23297Y-315092D01*
X-23821D01*
X-24033Y-314580D01*
X-24539Y-314074D01*
X-25059Y-313859D01*
Y-315600D01*
Y-317341D01*
X-24539Y-317126D01*
X-24033Y-316620D01*
X-23821Y-316108D01*
X-23297D01*
X-23085Y-316620D01*
X-22579Y-317126D01*
X-22059Y-317341D01*
Y-315600D01*
Y-313859D01*
D02*
G37*
G36*
X-21059D02*
Y-315100D01*
X-19818D01*
X-20033Y-314580D01*
X-20539Y-314074D01*
X-21059Y-313859D01*
D02*
G37*
G36*
X80504Y-314354D02*
X78331D01*
Y-315445D01*
X80504D01*
Y-314354D01*
D02*
G37*
G36*
X35252Y-287976D02*
X35003Y-287976D01*
X31996D01*
Y-291732D01*
Y-295488D01*
X35003D01*
X35252Y-295488D01*
X35669Y-295288D01*
X36966D01*
Y-314161D01*
X35421D01*
Y-315558D01*
X-3728D01*
Y-312044D01*
X-13202D01*
Y-321518D01*
X-3728D01*
Y-318005D01*
X35421D01*
Y-319698D01*
X38961D01*
Y-322236D01*
X43791D01*
Y-319669D01*
X41154D01*
Y-318153D01*
X51956D01*
Y-319501D01*
X56312D01*
Y-314357D01*
X51956D01*
Y-315706D01*
X41154D01*
Y-314189D01*
X43791D01*
Y-311122D01*
X44291D01*
Y-310622D01*
X49622D01*
Y-308055D01*
X46288D01*
X46011Y-307639D01*
X46033Y-307587D01*
X42550D01*
X42572Y-307639D01*
X42294Y-308055D01*
X39413D01*
Y-295288D01*
X40957D01*
Y-288176D01*
X35669D01*
X35252Y-287976D01*
D02*
G37*
G36*
X-19818Y-316100D02*
X-21059D01*
Y-317341D01*
X-20539Y-317126D01*
X-20033Y-316620D01*
X-19818Y-316100D01*
D02*
G37*
G36*
X49622Y-319669D02*
X44791D01*
Y-322236D01*
X49622D01*
Y-319669D01*
D02*
G37*
G36*
X21941Y-321859D02*
X21421Y-322074D01*
X20915Y-322580D01*
X20703Y-323092D01*
X20179D01*
X19967Y-322580D01*
X19461Y-322074D01*
X18941Y-321859D01*
Y-323600D01*
Y-325341D01*
X19461Y-325126D01*
X19967Y-324620D01*
X20179Y-324108D01*
X20703D01*
X20915Y-324620D01*
X21421Y-325126D01*
X21941Y-325341D01*
Y-323600D01*
Y-321859D01*
D02*
G37*
G36*
X17941D02*
X17421Y-322074D01*
X16915Y-322580D01*
X16703Y-323092D01*
X16179D01*
X15967Y-322580D01*
X15461Y-322074D01*
X14941Y-321859D01*
Y-323600D01*
Y-325341D01*
X15461Y-325126D01*
X15967Y-324620D01*
X16179Y-324108D01*
X16703D01*
X16915Y-324620D01*
X17421Y-325126D01*
X17941Y-325341D01*
Y-323600D01*
Y-321859D01*
D02*
G37*
G36*
X13941D02*
X13421Y-322074D01*
X12915Y-322580D01*
X12703Y-323092D01*
X12179D01*
X11967Y-322580D01*
X11461Y-322074D01*
X10941Y-321859D01*
Y-323600D01*
Y-325341D01*
X11461Y-325126D01*
X11967Y-324620D01*
X12179Y-324108D01*
X12703D01*
X12915Y-324620D01*
X13421Y-325126D01*
X13941Y-325341D01*
Y-323600D01*
Y-321859D01*
D02*
G37*
G36*
X54941D02*
Y-323100D01*
X56182D01*
X55967Y-322580D01*
X55461Y-322074D01*
X54941Y-321859D01*
D02*
G37*
G36*
X53941D02*
X53421Y-322074D01*
X52915Y-322580D01*
X52700Y-323100D01*
X53941D01*
Y-321859D01*
D02*
G37*
G36*
X34941D02*
Y-323100D01*
X36182D01*
X35967Y-322580D01*
X35461Y-322074D01*
X34941Y-321859D01*
D02*
G37*
G36*
X33941D02*
X33421Y-322074D01*
X32915Y-322580D01*
X32700Y-323100D01*
X33941D01*
Y-321859D01*
D02*
G37*
G36*
X22941D02*
Y-323100D01*
X24182D01*
X23967Y-322580D01*
X23461Y-322074D01*
X22941Y-321859D01*
D02*
G37*
G36*
X9941D02*
X9421Y-322074D01*
X8915Y-322580D01*
X8700Y-323100D01*
X9941D01*
Y-321859D01*
D02*
G37*
G36*
X36182Y-324100D02*
X34941D01*
Y-325341D01*
X35461Y-325126D01*
X35967Y-324620D01*
X36182Y-324100D01*
D02*
G37*
G36*
X33941D02*
X32700D01*
X32915Y-324620D01*
X33421Y-325126D01*
X33941Y-325341D01*
Y-324100D01*
D02*
G37*
G36*
X24182D02*
X22941D01*
Y-325341D01*
X23461Y-325126D01*
X23967Y-324620D01*
X24182Y-324100D01*
D02*
G37*
G36*
X9941D02*
X8700D01*
X8915Y-324620D01*
X9421Y-325126D01*
X9941Y-325341D01*
Y-324100D01*
D02*
G37*
G36*
X56182D02*
X54941D01*
Y-325341D01*
X55461Y-325126D01*
X55967Y-324620D01*
X56182Y-324100D01*
D02*
G37*
G36*
X53941D02*
X52700D01*
X52915Y-324620D01*
X53421Y-325126D01*
X53941Y-325341D01*
Y-324100D01*
D02*
G37*
G36*
X49622Y-323236D02*
X44291D01*
X38961D01*
Y-325803D01*
X42294D01*
X42572Y-326219D01*
X42550Y-326272D01*
X46033D01*
X46011Y-326219D01*
X46288Y-325803D01*
X49622D01*
Y-323236D01*
D02*
G37*
G36*
X-17763Y-321450D02*
X-17965D01*
Y-326281D01*
X-13134D01*
Y-326079D01*
X-13497Y-324724D01*
X-14199Y-323508D01*
X-15191Y-322516D01*
X-16407Y-321814D01*
X-17763Y-321450D01*
D02*
G37*
G36*
X2237D02*
X2035D01*
Y-326281D01*
X6866D01*
Y-326079D01*
X6503Y-324724D01*
X5801Y-323508D01*
X4809Y-322516D01*
X3593Y-321814D01*
X2237Y-321450D01*
D02*
G37*
G36*
X1035D02*
X834D01*
X-522Y-321814D01*
X-1738Y-322516D01*
X-2730Y-323508D01*
X-3432Y-324724D01*
X-3795Y-326079D01*
Y-326281D01*
X1035D01*
Y-321450D01*
D02*
G37*
G36*
X-18965D02*
X-19166D01*
X-20522Y-321814D01*
X-21738Y-322516D01*
X-22730Y-323508D01*
X-23432Y-324724D01*
X-23795Y-326079D01*
Y-326281D01*
X-18965D01*
Y-321450D01*
D02*
G37*
G36*
X85130Y-312235D02*
X84610Y-312450D01*
X84104Y-312957D01*
X83830Y-313618D01*
Y-314046D01*
X83522Y-314354D01*
X81504D01*
Y-315945D01*
X81004D01*
Y-316445D01*
X78331D01*
Y-317535D01*
X78531D01*
Y-320821D01*
X78081Y-320911D01*
X77684Y-321176D01*
X76891Y-321970D01*
X76626Y-322366D01*
X76532Y-322835D01*
Y-325787D01*
X76626Y-326256D01*
X76825Y-326554D01*
X76661Y-327054D01*
X76027D01*
Y-320866D01*
X75933Y-320398D01*
X75668Y-320001D01*
X74684Y-319017D01*
X74287Y-318752D01*
X73819Y-318658D01*
X71076D01*
Y-314554D01*
X66129D01*
Y-314721D01*
X65945D01*
X65477Y-314814D01*
X65080Y-315080D01*
X64454Y-315706D01*
X61824D01*
Y-314357D01*
X57468D01*
Y-319501D01*
X61824D01*
Y-318153D01*
X64454D01*
X65080Y-318778D01*
X65477Y-319044D01*
X65945Y-319137D01*
X66129D01*
Y-323241D01*
X70525D01*
Y-325435D01*
X68906Y-327054D01*
X64948D01*
Y-328399D01*
X63929D01*
X63898Y-328368D01*
X63310Y-328124D01*
X62674D01*
X62086Y-328368D01*
X61636Y-328818D01*
X61392Y-329406D01*
Y-330043D01*
X61636Y-330631D01*
X62086Y-331081D01*
X62674Y-331324D01*
X63310D01*
X63898Y-331081D01*
X63929Y-331050D01*
X64948D01*
Y-332366D01*
X64748D01*
Y-334933D01*
X71079D01*
Y-332366D01*
X70879D01*
Y-328830D01*
X71671Y-328038D01*
X72133Y-328229D01*
Y-332395D01*
X76914D01*
X77080Y-332677D01*
X76914Y-332960D01*
X72133D01*
Y-338300D01*
X73100D01*
X73206Y-338410D01*
X73389Y-338800D01*
X73203Y-339249D01*
Y-339885D01*
X73447Y-340473D01*
X73897Y-340923D01*
X74485Y-341167D01*
X75121D01*
X75709Y-340923D01*
X76160Y-340473D01*
X76403Y-339885D01*
Y-339249D01*
X76217Y-338800D01*
X76401Y-338410D01*
X76506Y-338300D01*
X77473Y-338300D01*
X77517Y-338782D01*
Y-339512D01*
X77384Y-339645D01*
X77140Y-340233D01*
Y-340869D01*
X77384Y-341458D01*
X77834Y-341908D01*
X78422Y-342151D01*
X79058D01*
X79646Y-341908D01*
X80097Y-341458D01*
X80340Y-340869D01*
Y-340233D01*
X80097Y-339645D01*
X79964Y-339512D01*
Y-338782D01*
X80007Y-338300D01*
X80464Y-338300D01*
X85347D01*
Y-336955D01*
X86661D01*
X86692Y-336986D01*
X87280Y-337230D01*
X87917D01*
X88505Y-336986D01*
X88955Y-336536D01*
X89198Y-335948D01*
Y-335312D01*
X88955Y-334724D01*
X88505Y-334274D01*
X87917Y-334030D01*
X87280D01*
X86692Y-334274D01*
X86661Y-334304D01*
X85347D01*
Y-332960D01*
X80566Y-332960D01*
X80401Y-332677D01*
X80566Y-332395D01*
X85347D01*
Y-331050D01*
X86661D01*
X86692Y-331081D01*
X87280Y-331324D01*
X87917D01*
X88505Y-331081D01*
X88955Y-330631D01*
X89198Y-330043D01*
Y-329406D01*
X88955Y-328818D01*
X88505Y-328368D01*
X87917Y-328124D01*
X87280D01*
X86692Y-328368D01*
X86661Y-328399D01*
X85347D01*
Y-327054D01*
X80753D01*
X78979Y-325281D01*
Y-323341D01*
X79056Y-323265D01*
X80813D01*
X80932Y-323241D01*
X83477D01*
Y-321105D01*
X84226D01*
X84273Y-321220D01*
X84724Y-321670D01*
X85312Y-321913D01*
X85948D01*
X86536Y-321670D01*
X86986Y-321220D01*
X87230Y-320632D01*
Y-319995D01*
X86986Y-319407D01*
X86536Y-318957D01*
X86743Y-318635D01*
X86772Y-318605D01*
X87016Y-318017D01*
Y-317381D01*
X86772Y-316793D01*
X86322Y-316343D01*
X86075Y-316240D01*
X86072Y-316223D01*
X86125Y-315720D01*
X86650Y-315502D01*
X87156Y-314996D01*
X87371Y-314476D01*
X85630D01*
Y-313976D01*
X85130D01*
Y-312235D01*
D02*
G37*
G36*
X35941Y-325859D02*
X35421Y-326074D01*
X34915Y-326580D01*
X34703Y-327092D01*
X34179D01*
X33967Y-326580D01*
X33461Y-326074D01*
X32941Y-325859D01*
Y-327600D01*
Y-329341D01*
X33461Y-329126D01*
X33967Y-328620D01*
X34179Y-328108D01*
X34703D01*
X34915Y-328620D01*
X35421Y-329126D01*
X35941Y-329341D01*
Y-327600D01*
Y-325859D01*
D02*
G37*
G36*
X31941D02*
X31421Y-326074D01*
X30915Y-326580D01*
X30703Y-327092D01*
X30179D01*
X29967Y-326580D01*
X29461Y-326074D01*
X28941Y-325859D01*
Y-327600D01*
Y-329341D01*
X29461Y-329126D01*
X29967Y-328620D01*
X30179Y-328108D01*
X30703D01*
X30915Y-328620D01*
X31421Y-329126D01*
X31941Y-329341D01*
Y-327600D01*
Y-325859D01*
D02*
G37*
G36*
X15941D02*
X15421Y-326074D01*
X14915Y-326580D01*
X14703Y-327092D01*
X14179D01*
X13967Y-326580D01*
X13461Y-326074D01*
X12941Y-325859D01*
Y-327600D01*
Y-329341D01*
X13461Y-329126D01*
X13967Y-328620D01*
X14179Y-328108D01*
X14703D01*
X14915Y-328620D01*
X15421Y-329126D01*
X15941Y-329341D01*
Y-327600D01*
Y-325859D01*
D02*
G37*
G36*
X55941D02*
X55421Y-326074D01*
X54915Y-326580D01*
X54703Y-327092D01*
X54179D01*
X53967Y-326580D01*
X53461Y-326074D01*
X52941Y-325859D01*
Y-327600D01*
Y-329341D01*
X53461Y-329126D01*
X53967Y-328620D01*
X54179Y-328108D01*
X54703D01*
X54915Y-328620D01*
X55421Y-329126D01*
X55941Y-329341D01*
Y-327600D01*
Y-325859D01*
D02*
G37*
G36*
X56941D02*
Y-327100D01*
X58182D01*
X57967Y-326580D01*
X57461Y-326074D01*
X56941Y-325859D01*
D02*
G37*
G36*
X51941D02*
X51421Y-326074D01*
X50915Y-326580D01*
X50700Y-327100D01*
X51941D01*
Y-325859D01*
D02*
G37*
G36*
X36941D02*
Y-327100D01*
X38182D01*
X37967Y-326580D01*
X37461Y-326074D01*
X36941Y-325859D01*
D02*
G37*
G36*
X27941D02*
X27421Y-326074D01*
X26915Y-326580D01*
X26700Y-327100D01*
X27941D01*
Y-325859D01*
D02*
G37*
G36*
X16941D02*
Y-327100D01*
X18182D01*
X17967Y-326580D01*
X17461Y-326074D01*
X16941Y-325859D01*
D02*
G37*
G36*
X11941D02*
X11421Y-326074D01*
X10915Y-326580D01*
X10700Y-327100D01*
X11941D01*
Y-325859D01*
D02*
G37*
G36*
X-7059D02*
Y-327100D01*
X-5818D01*
X-6033Y-326580D01*
X-6539Y-326074D01*
X-7059Y-325859D01*
D02*
G37*
G36*
X-8059D02*
X-8579Y-326074D01*
X-9085Y-326580D01*
X-9300Y-327100D01*
X-8059D01*
Y-325859D01*
D02*
G37*
G36*
X46033Y-327272D02*
X44791D01*
Y-328513D01*
X45311Y-328298D01*
X45817Y-327791D01*
X46033Y-327272D01*
D02*
G37*
G36*
X43791D02*
X42550D01*
X42765Y-327791D01*
X43272Y-328298D01*
X43791Y-328513D01*
Y-327272D01*
D02*
G37*
G36*
X38182Y-328100D02*
X36941D01*
Y-329341D01*
X37461Y-329126D01*
X37967Y-328620D01*
X38182Y-328100D01*
D02*
G37*
G36*
X27941D02*
X26700D01*
X26915Y-328620D01*
X27421Y-329126D01*
X27941Y-329341D01*
Y-328100D01*
D02*
G37*
G36*
X18182D02*
X16941D01*
Y-329341D01*
X17461Y-329126D01*
X17967Y-328620D01*
X18182Y-328100D01*
D02*
G37*
G36*
X11941D02*
X10700D01*
X10915Y-328620D01*
X11421Y-329126D01*
X11941Y-329341D01*
Y-328100D01*
D02*
G37*
G36*
X-5818D02*
X-7059D01*
Y-329341D01*
X-6539Y-329126D01*
X-6033Y-328620D01*
X-5818Y-328100D01*
D02*
G37*
G36*
X-8059D02*
X-9300D01*
X-9085Y-328620D01*
X-8579Y-329126D01*
X-8059Y-329341D01*
Y-328100D01*
D02*
G37*
G36*
X58182D02*
X56941D01*
Y-329341D01*
X57461Y-329126D01*
X57967Y-328620D01*
X58182Y-328100D01*
D02*
G37*
G36*
X51941D02*
X50700D01*
X50915Y-328620D01*
X51421Y-329126D01*
X51941Y-329341D01*
Y-328100D01*
D02*
G37*
G36*
X41941Y-329859D02*
X41421Y-330074D01*
X40915Y-330580D01*
X40703Y-331092D01*
X40179D01*
X39967Y-330580D01*
X39461Y-330074D01*
X38941Y-329859D01*
Y-331600D01*
Y-333341D01*
X39461Y-333126D01*
X39967Y-332620D01*
X40179Y-332108D01*
X40703D01*
X40915Y-332620D01*
X41421Y-333126D01*
X41941Y-333341D01*
Y-331600D01*
Y-329859D01*
D02*
G37*
G36*
X37941D02*
X37421Y-330074D01*
X36915Y-330580D01*
X36703Y-331092D01*
X36179D01*
X35967Y-330580D01*
X35461Y-330074D01*
X34941Y-329859D01*
Y-331600D01*
Y-333341D01*
X35461Y-333126D01*
X35967Y-332620D01*
X36179Y-332108D01*
X36703D01*
X36915Y-332620D01*
X37421Y-333126D01*
X37941Y-333341D01*
Y-331600D01*
Y-329859D01*
D02*
G37*
G36*
X33941D02*
X33421Y-330074D01*
X32915Y-330580D01*
X32703Y-331092D01*
X32179D01*
X31967Y-330580D01*
X31461Y-330074D01*
X30941Y-329859D01*
Y-331600D01*
Y-333341D01*
X31461Y-333126D01*
X31967Y-332620D01*
X32179Y-332108D01*
X32703D01*
X32915Y-332620D01*
X33421Y-333126D01*
X33941Y-333341D01*
Y-331600D01*
Y-329859D01*
D02*
G37*
G36*
X29941D02*
X29421Y-330074D01*
X28915Y-330580D01*
X28703Y-331092D01*
X28179D01*
X27967Y-330580D01*
X27461Y-330074D01*
X26941Y-329859D01*
Y-331600D01*
Y-333341D01*
X27461Y-333126D01*
X27967Y-332620D01*
X28179Y-332108D01*
X28703D01*
X28915Y-332620D01*
X29421Y-333126D01*
X29941Y-333341D01*
Y-331600D01*
Y-329859D01*
D02*
G37*
G36*
X13941D02*
X13421Y-330074D01*
X12915Y-330580D01*
X12703Y-331092D01*
X12179D01*
X11967Y-330580D01*
X11461Y-330074D01*
X10941Y-329859D01*
Y-331600D01*
Y-333341D01*
X11461Y-333126D01*
X11967Y-332620D01*
X12179Y-332108D01*
X12703D01*
X12915Y-332620D01*
X13421Y-333126D01*
X13941Y-333341D01*
Y-331600D01*
Y-329859D01*
D02*
G37*
G36*
X53941D02*
X53421Y-330074D01*
X52915Y-330580D01*
X52703Y-331092D01*
X52179D01*
X51967Y-330580D01*
X51461Y-330074D01*
X50941Y-329859D01*
Y-331600D01*
Y-333341D01*
X51461Y-333126D01*
X51967Y-332620D01*
X52179Y-332108D01*
X52703D01*
X52915Y-332620D01*
X53421Y-333126D01*
X53941Y-333341D01*
Y-331600D01*
Y-329859D01*
D02*
G37*
G36*
X49941D02*
X49421Y-330074D01*
X48915Y-330580D01*
X48703Y-331092D01*
X48179D01*
X47967Y-330580D01*
X47461Y-330074D01*
X46941Y-329859D01*
Y-331600D01*
Y-333341D01*
X47461Y-333126D01*
X47967Y-332620D01*
X48179Y-332108D01*
X48703D01*
X48915Y-332620D01*
X49421Y-333126D01*
X49941Y-333341D01*
Y-331600D01*
Y-329859D01*
D02*
G37*
G36*
X45941D02*
X45421Y-330074D01*
X44915Y-330580D01*
X44703Y-331092D01*
X44179D01*
X43967Y-330580D01*
X43461Y-330074D01*
X42941Y-329859D01*
Y-331600D01*
Y-333341D01*
X43461Y-333126D01*
X43967Y-332620D01*
X44179Y-332108D01*
X44703D01*
X44915Y-332620D01*
X45421Y-333126D01*
X45941Y-333341D01*
Y-331600D01*
Y-329859D01*
D02*
G37*
G36*
X54941D02*
Y-331100D01*
X56182D01*
X55967Y-330580D01*
X55461Y-330074D01*
X54941Y-329859D01*
D02*
G37*
G36*
X25941D02*
X25421Y-330074D01*
X24915Y-330580D01*
X24700Y-331100D01*
X25941D01*
Y-329859D01*
D02*
G37*
G36*
X14941D02*
Y-331100D01*
X16182D01*
X15967Y-330580D01*
X15461Y-330074D01*
X14941Y-329859D01*
D02*
G37*
G36*
X9941D02*
X9421Y-330074D01*
X8915Y-330580D01*
X8700Y-331100D01*
X9941D01*
Y-329859D01*
D02*
G37*
G36*
X-9059D02*
Y-331100D01*
X-7818D01*
X-8033Y-330580D01*
X-8539Y-330074D01*
X-9059Y-329859D01*
D02*
G37*
G36*
X-10059D02*
X-10579Y-330074D01*
X-11085Y-330580D01*
X-11300Y-331100D01*
X-10059D01*
Y-329859D01*
D02*
G37*
G36*
X6866Y-327281D02*
X2035D01*
Y-332112D01*
X2237D01*
X3593Y-331749D01*
X4809Y-331047D01*
X5801Y-330054D01*
X6503Y-328839D01*
X6866Y-327483D01*
Y-327281D01*
D02*
G37*
G36*
X1035D02*
X-3795D01*
Y-327483D01*
X-3432Y-328839D01*
X-2730Y-330054D01*
X-1738Y-331047D01*
X-522Y-331749D01*
X834Y-332112D01*
X1035D01*
Y-327281D01*
D02*
G37*
G36*
X-13134D02*
X-17965D01*
Y-332112D01*
X-17763D01*
X-16407Y-331749D01*
X-15191Y-331047D01*
X-14199Y-330054D01*
X-13497Y-328839D01*
X-13134Y-327483D01*
Y-327281D01*
D02*
G37*
G36*
X-18965D02*
X-23795D01*
Y-327483D01*
X-23432Y-328839D01*
X-22730Y-330054D01*
X-21738Y-331047D01*
X-20522Y-331749D01*
X-19166Y-332112D01*
X-18965D01*
Y-327281D01*
D02*
G37*
G36*
X25941Y-332100D02*
X24700D01*
X24915Y-332620D01*
X25421Y-333126D01*
X25941Y-333341D01*
Y-332100D01*
D02*
G37*
G36*
X16182D02*
X14941D01*
Y-333341D01*
X15461Y-333126D01*
X15967Y-332620D01*
X16182Y-332100D01*
D02*
G37*
G36*
X9941D02*
X8700D01*
X8915Y-332620D01*
X9421Y-333126D01*
X9941Y-333341D01*
Y-332100D01*
D02*
G37*
G36*
X-7818D02*
X-9059D01*
Y-333341D01*
X-8539Y-333126D01*
X-8033Y-332620D01*
X-7818Y-332100D01*
D02*
G37*
G36*
X-10059D02*
X-11300D01*
X-11085Y-332620D01*
X-10579Y-333126D01*
X-10059Y-333341D01*
Y-332100D01*
D02*
G37*
G36*
X56182D02*
X54941D01*
Y-333341D01*
X55461Y-333126D01*
X55967Y-332620D01*
X56182Y-332100D01*
D02*
G37*
G36*
X-15834Y-333846D02*
X-20977D01*
Y-334505D01*
X-22484D01*
X-22716Y-334274D01*
X-23304Y-334030D01*
X-23940D01*
X-24528Y-334274D01*
X-24979Y-334724D01*
X-25222Y-335312D01*
Y-335948D01*
X-24979Y-336536D01*
X-24528Y-336986D01*
X-23940Y-337230D01*
X-23304D01*
X-22716Y-336986D01*
X-22681Y-336952D01*
X-20977D01*
Y-337586D01*
X-21568D01*
Y-338343D01*
X-22583D01*
X-22716Y-338211D01*
X-23304Y-337967D01*
X-23940D01*
X-24528Y-338211D01*
X-24979Y-338661D01*
X-25222Y-339249D01*
Y-339885D01*
X-24979Y-340473D01*
X-24735Y-340717D01*
X-24584Y-341043D01*
X-24735Y-341370D01*
X-24979Y-341613D01*
X-25222Y-342201D01*
Y-342838D01*
X-24979Y-343426D01*
X-24528Y-343876D01*
X-23940Y-344120D01*
X-23304D01*
X-22764Y-343896D01*
X-21568D01*
Y-345091D01*
X-22004Y-345246D01*
X-22570D01*
X-22716Y-345100D01*
X-23304Y-344857D01*
X-23940D01*
X-24528Y-345100D01*
X-24979Y-345550D01*
X-25222Y-346138D01*
Y-346775D01*
X-24979Y-347363D01*
X-24528Y-347813D01*
X-23940Y-348057D01*
X-23304D01*
X-22918Y-347897D01*
X-20977D01*
Y-348832D01*
X-15834D01*
Y-344869D01*
X-17802D01*
Y-341548D01*
Y-337808D01*
X-15834D01*
Y-333846D01*
D02*
G37*
G36*
X43941Y-333859D02*
X43421Y-334074D01*
X42915Y-334580D01*
X42703Y-335092D01*
X42179D01*
X41967Y-334580D01*
X41461Y-334074D01*
X40941Y-333859D01*
Y-335600D01*
Y-337341D01*
X41461Y-337126D01*
X41967Y-336620D01*
X42179Y-336108D01*
X42703D01*
X42915Y-336620D01*
X43421Y-337126D01*
X43941Y-337341D01*
Y-335600D01*
Y-333859D01*
D02*
G37*
G36*
X39941D02*
X39421Y-334074D01*
X38915Y-334580D01*
X38703Y-335092D01*
X38179D01*
X37967Y-334580D01*
X37461Y-334074D01*
X36941Y-333859D01*
Y-335600D01*
Y-337341D01*
X37461Y-337126D01*
X37967Y-336620D01*
X38179Y-336108D01*
X38703D01*
X38915Y-336620D01*
X39421Y-337126D01*
X39941Y-337341D01*
Y-335600D01*
Y-333859D01*
D02*
G37*
G36*
X35941D02*
X35421Y-334074D01*
X34915Y-334580D01*
X34703Y-335092D01*
X34179D01*
X33967Y-334580D01*
X33461Y-334074D01*
X32941Y-333859D01*
Y-335600D01*
Y-337341D01*
X33461Y-337126D01*
X33967Y-336620D01*
X34179Y-336108D01*
X34703D01*
X34915Y-336620D01*
X35421Y-337126D01*
X35941Y-337341D01*
Y-335600D01*
Y-333859D01*
D02*
G37*
G36*
X31941D02*
X31421Y-334074D01*
X30915Y-334580D01*
X30703Y-335092D01*
X30179D01*
X29967Y-334580D01*
X29461Y-334074D01*
X28941Y-333859D01*
Y-335600D01*
Y-337341D01*
X29461Y-337126D01*
X29967Y-336620D01*
X30179Y-336108D01*
X30703D01*
X30915Y-336620D01*
X31421Y-337126D01*
X31941Y-337341D01*
Y-335600D01*
Y-333859D01*
D02*
G37*
G36*
X27941D02*
X27421Y-334074D01*
X26915Y-334580D01*
X26703Y-335092D01*
X26179D01*
X25967Y-334580D01*
X25461Y-334074D01*
X24941Y-333859D01*
Y-335600D01*
Y-337341D01*
X25461Y-337126D01*
X25967Y-336620D01*
X26179Y-336108D01*
X26703D01*
X26915Y-336620D01*
X27421Y-337126D01*
X27941Y-337341D01*
Y-335600D01*
Y-333859D01*
D02*
G37*
G36*
X23941D02*
X23421Y-334074D01*
X22915Y-334580D01*
X22703Y-335092D01*
X22179D01*
X21967Y-334580D01*
X21461Y-334074D01*
X20941Y-333859D01*
Y-335600D01*
Y-337341D01*
X21461Y-337126D01*
X21967Y-336620D01*
X22179Y-336108D01*
X22703D01*
X22915Y-336620D01*
X23421Y-337126D01*
X23941Y-337341D01*
Y-335600D01*
Y-333859D01*
D02*
G37*
G36*
X55941D02*
X55421Y-334074D01*
X54915Y-334580D01*
X54703Y-335092D01*
X54179D01*
X53967Y-334580D01*
X53461Y-334074D01*
X52941Y-333859D01*
Y-335600D01*
Y-337341D01*
X53461Y-337126D01*
X53967Y-336620D01*
X54179Y-336108D01*
X54703D01*
X54915Y-336620D01*
X55421Y-337126D01*
X55941Y-337341D01*
Y-335600D01*
Y-333859D01*
D02*
G37*
G36*
X51941D02*
X51421Y-334074D01*
X50915Y-334580D01*
X50703Y-335092D01*
X50179D01*
X49967Y-334580D01*
X49461Y-334074D01*
X48941Y-333859D01*
Y-335600D01*
Y-337341D01*
X49461Y-337126D01*
X49967Y-336620D01*
X50179Y-336108D01*
X50703D01*
X50915Y-336620D01*
X51421Y-337126D01*
X51941Y-337341D01*
Y-335600D01*
Y-333859D01*
D02*
G37*
G36*
X47941D02*
X47421Y-334074D01*
X46915Y-334580D01*
X46703Y-335092D01*
X46179D01*
X45967Y-334580D01*
X45461Y-334074D01*
X44941Y-333859D01*
Y-335600D01*
Y-337341D01*
X45461Y-337126D01*
X45967Y-336620D01*
X46179Y-336108D01*
X46703D01*
X46915Y-336620D01*
X47421Y-337126D01*
X47941Y-337341D01*
Y-335600D01*
Y-333859D01*
D02*
G37*
G36*
X56941D02*
Y-335100D01*
X58182D01*
X57967Y-334580D01*
X57461Y-334074D01*
X56941Y-333859D01*
D02*
G37*
G36*
X19941D02*
X19421Y-334074D01*
X18915Y-334580D01*
X18700Y-335100D01*
X19941D01*
Y-333859D01*
D02*
G37*
G36*
Y-336100D02*
X18700D01*
X18915Y-336620D01*
X19421Y-337126D01*
X19941Y-337341D01*
Y-336100D01*
D02*
G37*
G36*
X58182D02*
X56941D01*
Y-337341D01*
X57461Y-337126D01*
X57967Y-336620D01*
X58182Y-336100D01*
D02*
G37*
G36*
X41941Y-337859D02*
X41421Y-338074D01*
X40915Y-338580D01*
X40703Y-339092D01*
X40179D01*
X39967Y-338580D01*
X39461Y-338074D01*
X38941Y-337859D01*
Y-339600D01*
Y-341341D01*
X39461Y-341126D01*
X39967Y-340620D01*
X40179Y-340108D01*
X40703D01*
X40915Y-340620D01*
X41421Y-341126D01*
X41941Y-341341D01*
Y-339600D01*
Y-337859D01*
D02*
G37*
G36*
X37941D02*
X37421Y-338074D01*
X36915Y-338580D01*
X36703Y-339092D01*
X36179D01*
X35967Y-338580D01*
X35461Y-338074D01*
X34941Y-337859D01*
Y-339600D01*
Y-341341D01*
X35461Y-341126D01*
X35967Y-340620D01*
X36179Y-340108D01*
X36703D01*
X36915Y-340620D01*
X37421Y-341126D01*
X37941Y-341341D01*
Y-339600D01*
Y-337859D01*
D02*
G37*
G36*
X33941D02*
X33421Y-338074D01*
X32915Y-338580D01*
X32703Y-339092D01*
X32179D01*
X31967Y-338580D01*
X31461Y-338074D01*
X30941Y-337859D01*
Y-339600D01*
Y-341341D01*
X31461Y-341126D01*
X31967Y-340620D01*
X32179Y-340108D01*
X32703D01*
X32915Y-340620D01*
X33421Y-341126D01*
X33941Y-341341D01*
Y-339600D01*
Y-337859D01*
D02*
G37*
G36*
X29941D02*
X29421Y-338074D01*
X28915Y-338580D01*
X28703Y-339092D01*
X28179D01*
X27967Y-338580D01*
X27461Y-338074D01*
X26941Y-337859D01*
Y-339600D01*
Y-341341D01*
X27461Y-341126D01*
X27967Y-340620D01*
X28179Y-340108D01*
X28703D01*
X28915Y-340620D01*
X29421Y-341126D01*
X29941Y-341341D01*
Y-339600D01*
Y-337859D01*
D02*
G37*
G36*
X25941D02*
X25421Y-338074D01*
X24915Y-338580D01*
X24703Y-339092D01*
X24179D01*
X23967Y-338580D01*
X23461Y-338074D01*
X22941Y-337859D01*
Y-339600D01*
Y-341341D01*
X23461Y-341126D01*
X23967Y-340620D01*
X24179Y-340108D01*
X24703D01*
X24915Y-340620D01*
X25421Y-341126D01*
X25941Y-341341D01*
Y-339600D01*
Y-337859D01*
D02*
G37*
G36*
X21941D02*
X21421Y-338074D01*
X20915Y-338580D01*
X20703Y-339092D01*
X20179D01*
X19967Y-338580D01*
X19461Y-338074D01*
X18941Y-337859D01*
Y-339600D01*
Y-341341D01*
X19461Y-341126D01*
X19967Y-340620D01*
X20179Y-340108D01*
X20703D01*
X20915Y-340620D01*
X21421Y-341126D01*
X21941Y-341341D01*
Y-339600D01*
Y-337859D01*
D02*
G37*
G36*
X53941D02*
X53421Y-338074D01*
X52915Y-338580D01*
X52703Y-339092D01*
X52179D01*
X51967Y-338580D01*
X51461Y-338074D01*
X50941Y-337859D01*
Y-339600D01*
Y-341341D01*
X51461Y-341126D01*
X51967Y-340620D01*
X52179Y-340108D01*
X52703D01*
X52915Y-340620D01*
X53421Y-341126D01*
X53941Y-341341D01*
Y-339600D01*
Y-337859D01*
D02*
G37*
G36*
X49941D02*
X49421Y-338074D01*
X48915Y-338580D01*
X48703Y-339092D01*
X48179D01*
X47967Y-338580D01*
X47461Y-338074D01*
X46941Y-337859D01*
Y-339600D01*
Y-341341D01*
X47461Y-341126D01*
X47967Y-340620D01*
X48179Y-340108D01*
X48703D01*
X48915Y-340620D01*
X49421Y-341126D01*
X49941Y-341341D01*
Y-339600D01*
Y-337859D01*
D02*
G37*
G36*
X45941D02*
X45421Y-338074D01*
X44915Y-338580D01*
X44703Y-339092D01*
X44179D01*
X43967Y-338580D01*
X43461Y-338074D01*
X42941Y-337859D01*
Y-339600D01*
Y-341341D01*
X43461Y-341126D01*
X43967Y-340620D01*
X44179Y-340108D01*
X44703D01*
X44915Y-340620D01*
X45421Y-341126D01*
X45941Y-341341D01*
Y-339600D01*
Y-337859D01*
D02*
G37*
G36*
X54941D02*
Y-339100D01*
X56182D01*
X55967Y-338580D01*
X55461Y-338074D01*
X54941Y-337859D01*
D02*
G37*
G36*
X17941D02*
X17421Y-338074D01*
X16915Y-338580D01*
X16700Y-339100D01*
X17941D01*
Y-337859D01*
D02*
G37*
G36*
X71079Y-335933D02*
X64748D01*
Y-338500D01*
X66690D01*
Y-339229D01*
X66387Y-339532D01*
X66172Y-340051D01*
X69655D01*
X69439Y-339532D01*
X69137Y-339229D01*
Y-338500D01*
X71079D01*
Y-335933D01*
D02*
G37*
G36*
X56182Y-340100D02*
X54941D01*
Y-341341D01*
X55461Y-341126D01*
X55967Y-340620D01*
X56182Y-340100D01*
D02*
G37*
G36*
X17941D02*
X16700D01*
X16915Y-340620D01*
X17421Y-341126D01*
X17941Y-341341D01*
Y-340100D01*
D02*
G37*
G36*
X69655Y-341051D02*
X68413D01*
Y-342292D01*
X68933Y-342077D01*
X69439Y-341571D01*
X69655Y-341051D01*
D02*
G37*
G36*
X67413D02*
X66172D01*
X66387Y-341571D01*
X66894Y-342077D01*
X67413Y-342292D01*
Y-341051D01*
D02*
G37*
G36*
X43941Y-341859D02*
X43421Y-342074D01*
X42915Y-342580D01*
X42703Y-343092D01*
X42179D01*
X41967Y-342580D01*
X41461Y-342074D01*
X40941Y-341859D01*
Y-343600D01*
Y-345341D01*
X41461Y-345126D01*
X41967Y-344620D01*
X42179Y-344108D01*
X42703D01*
X42915Y-344620D01*
X43421Y-345126D01*
X43941Y-345341D01*
Y-343600D01*
Y-341859D01*
D02*
G37*
G36*
X39941D02*
X39421Y-342074D01*
X38915Y-342580D01*
X38703Y-343092D01*
X38179D01*
X37967Y-342580D01*
X37461Y-342074D01*
X36941Y-341859D01*
Y-343600D01*
Y-345341D01*
X37461Y-345126D01*
X37967Y-344620D01*
X38179Y-344108D01*
X38703D01*
X38915Y-344620D01*
X39421Y-345126D01*
X39941Y-345341D01*
Y-343600D01*
Y-341859D01*
D02*
G37*
G36*
X35941D02*
X35421Y-342074D01*
X34915Y-342580D01*
X34703Y-343092D01*
X34179D01*
X33967Y-342580D01*
X33461Y-342074D01*
X32941Y-341859D01*
Y-343600D01*
Y-345341D01*
X33461Y-345126D01*
X33967Y-344620D01*
X34179Y-344108D01*
X34703D01*
X34915Y-344620D01*
X35421Y-345126D01*
X35941Y-345341D01*
Y-343600D01*
Y-341859D01*
D02*
G37*
G36*
X31941D02*
X31421Y-342074D01*
X30915Y-342580D01*
X30703Y-343092D01*
X30179D01*
X29967Y-342580D01*
X29461Y-342074D01*
X28941Y-341859D01*
Y-343600D01*
Y-345341D01*
X29461Y-345126D01*
X29967Y-344620D01*
X30179Y-344108D01*
X30703D01*
X30915Y-344620D01*
X31421Y-345126D01*
X31941Y-345341D01*
Y-343600D01*
Y-341859D01*
D02*
G37*
G36*
X27941D02*
X27421Y-342074D01*
X26915Y-342580D01*
X26703Y-343092D01*
X26179D01*
X25967Y-342580D01*
X25461Y-342074D01*
X24941Y-341859D01*
Y-343600D01*
Y-345341D01*
X25461Y-345126D01*
X25967Y-344620D01*
X26179Y-344108D01*
X26703D01*
X26915Y-344620D01*
X27421Y-345126D01*
X27941Y-345341D01*
Y-343600D01*
Y-341859D01*
D02*
G37*
G36*
X23941D02*
X23421Y-342074D01*
X22915Y-342580D01*
X22703Y-343092D01*
X22179D01*
X21967Y-342580D01*
X21461Y-342074D01*
X20941Y-341859D01*
Y-343600D01*
Y-345341D01*
X21461Y-345126D01*
X21967Y-344620D01*
X22179Y-344108D01*
X22703D01*
X22915Y-344620D01*
X23421Y-345126D01*
X23941Y-345341D01*
Y-343600D01*
Y-341859D01*
D02*
G37*
G36*
X19941D02*
X19421Y-342074D01*
X18915Y-342580D01*
X18703Y-343092D01*
X18179D01*
X17967Y-342580D01*
X17461Y-342074D01*
X16941Y-341859D01*
Y-343600D01*
Y-345341D01*
X17461Y-345126D01*
X17967Y-344620D01*
X18179Y-344108D01*
X18703D01*
X18915Y-344620D01*
X19421Y-345126D01*
X19941Y-345341D01*
Y-343600D01*
Y-341859D01*
D02*
G37*
G36*
X15941D02*
X15421Y-342074D01*
X14915Y-342580D01*
X14703Y-343092D01*
X14179D01*
X13967Y-342580D01*
X13461Y-342074D01*
X12941Y-341859D01*
Y-343600D01*
Y-345341D01*
X13461Y-345126D01*
X13967Y-344620D01*
X14179Y-344108D01*
X14703D01*
X14915Y-344620D01*
X15421Y-345126D01*
X15941Y-345341D01*
Y-343600D01*
Y-341859D01*
D02*
G37*
G36*
X55941D02*
X55421Y-342074D01*
X54915Y-342580D01*
X54703Y-343092D01*
X54179D01*
X53967Y-342580D01*
X53461Y-342074D01*
X52941Y-341859D01*
Y-343600D01*
Y-345341D01*
X53461Y-345126D01*
X53967Y-344620D01*
X54179Y-344108D01*
X54703D01*
X54915Y-344620D01*
X55421Y-345126D01*
X55941Y-345341D01*
Y-343600D01*
Y-341859D01*
D02*
G37*
G36*
X51941D02*
X51421Y-342074D01*
X50915Y-342580D01*
X50703Y-343092D01*
X50179D01*
X49967Y-342580D01*
X49461Y-342074D01*
X48941Y-341859D01*
Y-343600D01*
Y-345341D01*
X49461Y-345126D01*
X49967Y-344620D01*
X50179Y-344108D01*
X50703D01*
X50915Y-344620D01*
X51421Y-345126D01*
X51941Y-345341D01*
Y-343600D01*
Y-341859D01*
D02*
G37*
G36*
X47941D02*
X47421Y-342074D01*
X46915Y-342580D01*
X46703Y-343092D01*
X46179D01*
X45967Y-342580D01*
X45461Y-342074D01*
X44941Y-341859D01*
Y-343600D01*
Y-345341D01*
X45461Y-345126D01*
X45967Y-344620D01*
X46179Y-344108D01*
X46703D01*
X46915Y-344620D01*
X47421Y-345126D01*
X47941Y-345341D01*
Y-343600D01*
Y-341859D01*
D02*
G37*
G36*
X56941D02*
Y-343100D01*
X58182D01*
X57967Y-342580D01*
X57461Y-342074D01*
X56941Y-341859D01*
D02*
G37*
G36*
X11941D02*
X11421Y-342074D01*
X10915Y-342580D01*
X10700Y-343100D01*
X11941D01*
Y-341859D01*
D02*
G37*
G36*
X58182Y-344100D02*
X56941D01*
Y-345341D01*
X57461Y-345126D01*
X57967Y-344620D01*
X58182Y-344100D01*
D02*
G37*
G36*
X11941D02*
X10700D01*
X10915Y-344620D01*
X11421Y-345126D01*
X11941Y-345341D01*
Y-344100D01*
D02*
G37*
G36*
X43941Y-349859D02*
X43421Y-350074D01*
X42915Y-350580D01*
X42703Y-351092D01*
X42179D01*
X41967Y-350580D01*
X41461Y-350074D01*
X40941Y-349859D01*
Y-351600D01*
Y-353341D01*
X41461Y-353126D01*
X41967Y-352620D01*
X42179Y-352108D01*
X42703D01*
X42915Y-352620D01*
X43421Y-353126D01*
X43941Y-353341D01*
Y-351600D01*
Y-349859D01*
D02*
G37*
G36*
X39941D02*
X39421Y-350074D01*
X38915Y-350580D01*
X38703Y-351092D01*
X38179D01*
X37967Y-350580D01*
X37461Y-350074D01*
X36941Y-349859D01*
Y-351600D01*
Y-353341D01*
X37461Y-353126D01*
X37967Y-352620D01*
X38179Y-352108D01*
X38703D01*
X38915Y-352620D01*
X39421Y-353126D01*
X39941Y-353341D01*
Y-351600D01*
Y-349859D01*
D02*
G37*
G36*
X35941D02*
X35421Y-350074D01*
X34915Y-350580D01*
X34703Y-351092D01*
X34179D01*
X33967Y-350580D01*
X33461Y-350074D01*
X32941Y-349859D01*
Y-351600D01*
Y-353341D01*
X33461Y-353126D01*
X33967Y-352620D01*
X34179Y-352108D01*
X34703D01*
X34915Y-352620D01*
X35421Y-353126D01*
X35941Y-353341D01*
Y-351600D01*
Y-349859D01*
D02*
G37*
G36*
X31941D02*
X31421Y-350074D01*
X30915Y-350580D01*
X30703Y-351092D01*
X30179D01*
X29967Y-350580D01*
X29461Y-350074D01*
X28941Y-349859D01*
Y-351600D01*
Y-353341D01*
X29461Y-353126D01*
X29967Y-352620D01*
X30179Y-352108D01*
X30703D01*
X30915Y-352620D01*
X31421Y-353126D01*
X31941Y-353341D01*
Y-351600D01*
Y-349859D01*
D02*
G37*
G36*
X27941D02*
X27421Y-350074D01*
X26915Y-350580D01*
X26703Y-351092D01*
X26179D01*
X25967Y-350580D01*
X25461Y-350074D01*
X24941Y-349859D01*
Y-351600D01*
Y-353341D01*
X25461Y-353126D01*
X25967Y-352620D01*
X26179Y-352108D01*
X26703D01*
X26915Y-352620D01*
X27421Y-353126D01*
X27941Y-353341D01*
Y-351600D01*
Y-349859D01*
D02*
G37*
G36*
X23941D02*
X23421Y-350074D01*
X22915Y-350580D01*
X22703Y-351092D01*
X22179D01*
X21967Y-350580D01*
X21461Y-350074D01*
X20941Y-349859D01*
Y-351600D01*
Y-353341D01*
X21461Y-353126D01*
X21967Y-352620D01*
X22179Y-352108D01*
X22703D01*
X22915Y-352620D01*
X23421Y-353126D01*
X23941Y-353341D01*
Y-351600D01*
Y-349859D01*
D02*
G37*
G36*
X19941D02*
X19421Y-350074D01*
X18915Y-350580D01*
X18703Y-351092D01*
X18179D01*
X17967Y-350580D01*
X17461Y-350074D01*
X16941Y-349859D01*
Y-351600D01*
Y-353341D01*
X17461Y-353126D01*
X17967Y-352620D01*
X18179Y-352108D01*
X18703D01*
X18915Y-352620D01*
X19421Y-353126D01*
X19941Y-353341D01*
Y-351600D01*
Y-349859D01*
D02*
G37*
G36*
X15941D02*
X15421Y-350074D01*
X14915Y-350580D01*
X14703Y-351092D01*
X14179D01*
X13967Y-350580D01*
X13461Y-350074D01*
X12941Y-349859D01*
Y-351600D01*
Y-353341D01*
X13461Y-353126D01*
X13967Y-352620D01*
X14179Y-352108D01*
X14703D01*
X14915Y-352620D01*
X15421Y-353126D01*
X15941Y-353341D01*
Y-351600D01*
Y-349859D01*
D02*
G37*
G36*
X11941D02*
X11421Y-350074D01*
X10915Y-350580D01*
X10703Y-351092D01*
X10179D01*
X9967Y-350580D01*
X9461Y-350074D01*
X8941Y-349859D01*
Y-351600D01*
Y-353341D01*
X9461Y-353126D01*
X9967Y-352620D01*
X10179Y-352108D01*
X10703D01*
X10915Y-352620D01*
X11421Y-353126D01*
X11941Y-353341D01*
Y-351600D01*
Y-349859D01*
D02*
G37*
G36*
X7941D02*
X7421Y-350074D01*
X6915Y-350580D01*
X6703Y-351092D01*
X6179D01*
X5967Y-350580D01*
X5461Y-350074D01*
X4941Y-349859D01*
Y-351600D01*
Y-353341D01*
X5461Y-353126D01*
X5967Y-352620D01*
X6179Y-352108D01*
X6703D01*
X6915Y-352620D01*
X7421Y-353126D01*
X7941Y-353341D01*
Y-351600D01*
Y-349859D01*
D02*
G37*
G36*
X3941D02*
X3421Y-350074D01*
X2915Y-350580D01*
X2703Y-351092D01*
X2179D01*
X1967Y-350580D01*
X1461Y-350074D01*
X941Y-349859D01*
Y-351600D01*
Y-353341D01*
X1461Y-353126D01*
X1967Y-352620D01*
X2179Y-352108D01*
X2703D01*
X2915Y-352620D01*
X3421Y-353126D01*
X3941Y-353341D01*
Y-351600D01*
Y-349859D01*
D02*
G37*
G36*
X-59D02*
X-579Y-350074D01*
X-1085Y-350580D01*
X-1297Y-351092D01*
X-1821D01*
X-2033Y-350580D01*
X-2539Y-350074D01*
X-3059Y-349859D01*
Y-351600D01*
Y-353341D01*
X-2539Y-353126D01*
X-2033Y-352620D01*
X-1821Y-352108D01*
X-1297D01*
X-1085Y-352620D01*
X-579Y-353126D01*
X-59Y-353341D01*
Y-351600D01*
Y-349859D01*
D02*
G37*
G36*
X-4059D02*
X-4579Y-350074D01*
X-5085Y-350580D01*
X-5297Y-351092D01*
X-5821D01*
X-6033Y-350580D01*
X-6539Y-350074D01*
X-7059Y-349859D01*
Y-351600D01*
Y-353341D01*
X-6539Y-353126D01*
X-6033Y-352620D01*
X-5821Y-352108D01*
X-5297D01*
X-5085Y-352620D01*
X-4579Y-353126D01*
X-4059Y-353341D01*
Y-351600D01*
Y-349859D01*
D02*
G37*
G36*
X-8059D02*
X-8579Y-350074D01*
X-9085Y-350580D01*
X-9297Y-351092D01*
X-9821D01*
X-10033Y-350580D01*
X-10539Y-350074D01*
X-11059Y-349859D01*
Y-351600D01*
Y-353341D01*
X-10539Y-353126D01*
X-10033Y-352620D01*
X-9821Y-352108D01*
X-9297D01*
X-9085Y-352620D01*
X-8579Y-353126D01*
X-8059Y-353341D01*
Y-351600D01*
Y-349859D01*
D02*
G37*
G36*
X-12059D02*
X-12579Y-350074D01*
X-13085Y-350580D01*
X-13297Y-351092D01*
X-13821D01*
X-14033Y-350580D01*
X-14539Y-350074D01*
X-15059Y-349859D01*
Y-351600D01*
Y-353341D01*
X-14539Y-353126D01*
X-14033Y-352620D01*
X-13821Y-352108D01*
X-13297D01*
X-13085Y-352620D01*
X-12579Y-353126D01*
X-12059Y-353341D01*
Y-351600D01*
Y-349859D01*
D02*
G37*
G36*
X-16059D02*
X-16579Y-350074D01*
X-17085Y-350580D01*
X-17297Y-351092D01*
X-17821D01*
X-18033Y-350580D01*
X-18539Y-350074D01*
X-19059Y-349859D01*
Y-351600D01*
Y-353341D01*
X-18539Y-353126D01*
X-18033Y-352620D01*
X-17821Y-352108D01*
X-17297D01*
X-17085Y-352620D01*
X-16579Y-353126D01*
X-16059Y-353341D01*
Y-351600D01*
Y-349859D01*
D02*
G37*
G36*
X-20059D02*
X-20579Y-350074D01*
X-21085Y-350580D01*
X-21297Y-351092D01*
X-21821D01*
X-22033Y-350580D01*
X-22539Y-350074D01*
X-23059Y-349859D01*
Y-351600D01*
Y-353341D01*
X-22539Y-353126D01*
X-22033Y-352620D01*
X-21821Y-352108D01*
X-21297D01*
X-21085Y-352620D01*
X-20579Y-353126D01*
X-20059Y-353341D01*
Y-351600D01*
Y-349859D01*
D02*
G37*
G36*
X55941D02*
X55421Y-350074D01*
X54915Y-350580D01*
X54703Y-351092D01*
X54179D01*
X53967Y-350580D01*
X53461Y-350074D01*
X52941Y-349859D01*
Y-351600D01*
Y-353341D01*
X53461Y-353126D01*
X53967Y-352620D01*
X54179Y-352108D01*
X54703D01*
X54915Y-352620D01*
X55421Y-353126D01*
X55941Y-353341D01*
Y-351600D01*
Y-349859D01*
D02*
G37*
G36*
X51941D02*
X51421Y-350074D01*
X50915Y-350580D01*
X50703Y-351092D01*
X50179D01*
X49967Y-350580D01*
X49461Y-350074D01*
X48941Y-349859D01*
Y-351600D01*
Y-353341D01*
X49461Y-353126D01*
X49967Y-352620D01*
X50179Y-352108D01*
X50703D01*
X50915Y-352620D01*
X51421Y-353126D01*
X51941Y-353341D01*
Y-351600D01*
Y-349859D01*
D02*
G37*
G36*
X47941D02*
X47421Y-350074D01*
X46915Y-350580D01*
X46703Y-351092D01*
X46179D01*
X45967Y-350580D01*
X45461Y-350074D01*
X44941Y-349859D01*
Y-351600D01*
Y-353341D01*
X45461Y-353126D01*
X45967Y-352620D01*
X46179Y-352108D01*
X46703D01*
X46915Y-352620D01*
X47421Y-353126D01*
X47941Y-353341D01*
Y-351600D01*
Y-349859D01*
D02*
G37*
G36*
X56941D02*
Y-351100D01*
X58182D01*
X57967Y-350580D01*
X57461Y-350074D01*
X56941Y-349859D01*
D02*
G37*
G36*
X-24059D02*
X-24579Y-350074D01*
X-25085Y-350580D01*
X-25300Y-351100D01*
X-24059D01*
Y-349859D01*
D02*
G37*
G36*
X58182Y-352100D02*
X56941D01*
Y-353341D01*
X57461Y-353126D01*
X57967Y-352620D01*
X58182Y-352100D01*
D02*
G37*
G36*
X-24059D02*
X-25300D01*
X-25085Y-352620D01*
X-24579Y-353126D01*
X-24059Y-353341D01*
Y-352100D01*
D02*
G37*
%LPD*%
D10*
X546419Y-241862D02*
X547376Y-240905D01*
X546419Y-246106D02*
Y-241862D01*
X554519Y-216156D02*
Y-212889D01*
X554419Y-216256D02*
X554519Y-216156D01*
X626762Y-243949D02*
X626819Y-244005D01*
X610919Y-243949D02*
X611094Y-244124D01*
Y-248110D02*
Y-244124D01*
X591978Y-247441D02*
Y-242657D01*
X586466Y-247441D02*
Y-242646D01*
X621919Y-243949D02*
X626762D01*
X581853Y-233228D02*
X582135D01*
X580935Y-234146D02*
X581853Y-233228D01*
X580935Y-237412D02*
Y-234146D01*
X575919Y-243150D02*
Y-236906D01*
X591919Y-242598D02*
X591978Y-242657D01*
X335483Y-244859D02*
X337070D01*
X338362Y-243567D01*
X338525D01*
X343149Y-225168D02*
X348915D01*
X343144Y-225173D02*
X343149Y-225168D01*
X343492Y-215325D02*
X348915D01*
X343444Y-215373D02*
X343492Y-215325D01*
X431889Y-298089D02*
Y-294306D01*
X432283Y-293912D01*
Y-293750D01*
X343009Y-264538D02*
X348915D01*
X342944Y-264473D02*
X343009Y-264538D01*
X332971Y-225168D02*
X332976Y-225173D01*
X338444D01*
X348747Y-205651D02*
X348915Y-205483D01*
X343403Y-205651D02*
X348747D01*
X343222Y-254695D02*
X348915D01*
X343144Y-254773D02*
X343222Y-254695D01*
X431928Y-316492D02*
Y-311189D01*
X432144Y-310973D01*
X332971Y-215325D02*
X338792D01*
X338844Y-215273D01*
X332971Y-264538D02*
X338379D01*
X338444Y-264473D01*
X344026Y-244867D02*
X346325D01*
X342906Y-243747D02*
X344026Y-244867D01*
X342744Y-243747D02*
X342906D01*
X332971Y-205483D02*
X338734D01*
X338744Y-205473D01*
X335840Y-254673D02*
X338344D01*
X335826Y-254687D02*
X335840Y-254673D01*
X332971Y-254695D02*
X332979Y-254687D01*
X335826D01*
X338344Y-254673D02*
X338444Y-254773D01*
X639658Y-320283D02*
Y-314672D01*
X639750Y-314581D01*
X639567Y-320374D02*
X639658Y-320283D01*
X658532Y-320208D02*
Y-314696D01*
X658647Y-314581D01*
X658268Y-320473D02*
X658532Y-320208D01*
X509496Y-345229D02*
X515008D01*
X509405Y-345138D02*
X509496Y-345229D01*
X515008D02*
X515099Y-345321D01*
X509173Y-330177D02*
X510172Y-329179D01*
X515198D01*
X509011Y-330177D02*
X509173D01*
X71850Y-151575D02*
Y-147638D01*
Y-151575D02*
X76772Y-156496D01*
X81004D01*
X75787Y-127756D02*
X75787Y-127756D01*
X75787Y-131890D02*
Y-127756D01*
X87590Y-126960D02*
X88566Y-125984D01*
X94193D01*
X76772Y-135827D02*
Y-132874D01*
X75787Y-131890D02*
X76772Y-132874D01*
X643701Y-63976D02*
Y-58907D01*
X644685Y-50049D02*
X644685Y-50049D01*
X644685Y-50049D02*
Y-45276D01*
X623000Y-37402D02*
X625586D01*
X625832Y-37647D02*
X631890D01*
X625586Y-37402D02*
X625832Y-37647D01*
X610010Y-14017D02*
Y-9246D01*
X610236Y-9021D01*
Y-8858D01*
X609252Y-26575D02*
Y-21506D01*
X89567Y-102362D02*
Y-98277D01*
X89567Y-98277D01*
X98425Y-102362D02*
Y-98080D01*
X98425Y-98080D01*
X570565Y-105662D02*
X570727D01*
X570218Y-105315D02*
X570565Y-105662D01*
X566644Y-105315D02*
X570218D01*
X87590Y-126977D02*
Y-126960D01*
X85827Y-128740D02*
X87590Y-126977D01*
X75984Y-127953D02*
X78740D01*
X75787Y-127756D02*
X75984Y-127953D01*
X79528Y-128740D02*
X82677D01*
X78740Y-127953D02*
X79528Y-128740D01*
X82677D02*
X85827D01*
X120677Y-81447D02*
Y-81340D01*
X538770Y-144462D02*
Y-138406D01*
Y-144462D02*
X538813Y-144506D01*
X544813Y-114256D02*
Y-109806D01*
X566813Y-140150D02*
Y-132405D01*
X548425Y-150787D02*
X551813Y-147399D01*
Y-140150D01*
X634252Y-314729D02*
X634449Y-314926D01*
X634252Y-314729D02*
Y-314567D01*
X634449Y-320374D02*
Y-314926D01*
X653150Y-320473D02*
Y-314567D01*
X509489Y-350537D02*
X515001D01*
X515099Y-350439D01*
X509391Y-350636D02*
X509489Y-350537D01*
X509160Y-335675D02*
X510537Y-334297D01*
X515198D01*
X508997Y-335675D02*
X509160D01*
X241107Y-133465D02*
X242295Y-132277D01*
X257294D01*
X240945Y-133465D02*
X241107D01*
X71029Y-122047D02*
X72013Y-123031D01*
X70866Y-122047D02*
X71029D01*
X72013Y-123031D02*
X82480D01*
X82677Y-175197D02*
X86614D01*
X82677Y-175197D02*
X82677Y-175197D01*
X75787Y-232283D02*
Y-227362D01*
X72835Y-215551D02*
X73503Y-216220D01*
X68898Y-221654D02*
X68996D01*
X73503Y-217146D01*
Y-216220D01*
X69587Y-215551D02*
X72835D01*
X64139Y-221457D02*
X64336Y-221654D01*
X63976Y-221457D02*
X64139D01*
X64336Y-221654D02*
X68898D01*
X75787Y-227362D02*
X75787Y-227362D01*
X82677Y-227362D02*
X86614D01*
X63976Y-275590D02*
X68701D01*
X68898Y-275787D01*
X68996D01*
X73819Y-270965D01*
X72835Y-267717D02*
X73819Y-268701D01*
Y-270965D02*
Y-268701D01*
X69587Y-267717D02*
X72835D01*
X75787Y-285433D02*
Y-281496D01*
X83661D02*
X87598D01*
X82677Y-329724D02*
X87598D01*
X82677Y-335630D02*
X87598D01*
X74803Y-339567D02*
Y-335630D01*
X67716Y-329724D02*
X67913Y-329921D01*
X62992Y-329724D02*
X67716D01*
X68012Y-329921D02*
X69579Y-328354D01*
Y-328256D01*
X71850Y-325984D01*
Y-322436D01*
X67913Y-329921D02*
X68012D01*
X71265Y-321850D02*
X71850Y-322436D01*
X68602Y-321850D02*
X71265D01*
X71850Y-165650D02*
Y-162987D01*
X67913Y-169488D02*
X68012D01*
X71850Y-165650D01*
X68602Y-162402D02*
X71265D01*
X71850Y-162987D01*
X74803Y-179134D02*
Y-175197D01*
X63976Y-179134D02*
Y-170276D01*
X64764Y-169488D02*
X67913D01*
X63976Y-170276D02*
X64764Y-169488D01*
X26575Y-283465D02*
X26737D01*
X27131Y-283071D02*
X30709D01*
X26737Y-283465D02*
X27131Y-283071D01*
X30512Y-170438D02*
X30709Y-170635D01*
X30512Y-170438D02*
Y-170276D01*
X30709Y-175394D02*
Y-170635D01*
X-23507Y-241027D02*
X-18881D01*
X-23622Y-241142D02*
X-23507Y-241027D01*
X-18881D02*
X-18406Y-240551D01*
X-23507Y-346571D02*
X-18684D01*
X-23622Y-346457D02*
X-23507Y-346571D01*
X-18684D02*
X-18406Y-346850D01*
X-23524Y-294193D02*
X-18504D01*
X-18406Y-294094D01*
X-23622Y-294291D02*
X-23524Y-294193D01*
X-23622Y-187992D02*
X-23524Y-187894D01*
X-18504D02*
X-18406Y-187795D01*
X-23524Y-187894D02*
X-18504D01*
X-23524Y-114075D02*
X-18504D01*
X-18406Y-113976D01*
X-23622Y-114173D02*
X-23524Y-114075D01*
X-23622Y-70866D02*
X-23524Y-70768D01*
X-18504D02*
X-18406Y-70669D01*
X-23524Y-70768D02*
X-18504D01*
X82677Y-135827D02*
X85630Y-132874D01*
Y-131890D01*
X85630D01*
X89567Y-127953D02*
X94193D01*
X85630Y-131890D02*
X89567Y-127953D01*
X86614Y-123031D02*
X87598Y-124016D01*
X94193D01*
X82480Y-123031D02*
X82677Y-123228D01*
X82874Y-123031D02*
X86614D01*
X82677Y-123228D02*
X82874Y-123031D01*
X75884Y-116535D02*
X82677D01*
X75845Y-116496D02*
X75884Y-116535D01*
X83268Y-117126D02*
X86614D01*
X82677Y-116535D02*
X83268Y-117126D01*
X86614D02*
X89567Y-120079D01*
X94193D01*
D18*
X199898Y-119399D02*
G03*
X199803Y-119439I0J-134D01*
G01*
X264354Y-399013D02*
G03*
X265354Y-401427I3414J0D01*
G01*
X199804Y-114517D02*
G03*
X199803Y-114517I285J-286D01*
G01*
X200088Y-114399D02*
G03*
X199804Y-114517I0J-403D01*
G01*
X405512Y-136611D02*
Y-134695D01*
X416123Y-152551D02*
Y-144197D01*
X313839Y-245593D02*
X314658Y-244775D01*
X309193Y-245593D02*
X313839D01*
X313610Y-233593D02*
X315097Y-235081D01*
X309193Y-233593D02*
X313610D01*
X314267Y-231593D02*
X315226Y-230634D01*
X309193Y-231593D02*
X314267D01*
X313268Y-229593D02*
X314864Y-227997D01*
X309193Y-229593D02*
X313268D01*
X312089Y-227593D02*
X314503Y-225180D01*
X309193Y-227593D02*
X312089D01*
X288057Y-233478D02*
X288173Y-233593D01*
X293445D01*
X288189Y-231102D02*
X288680Y-231593D01*
X293445D01*
X288189Y-228740D02*
X289042Y-229593D01*
X293445D01*
X288583Y-225590D02*
X290585Y-227593D01*
X293445D01*
X288189Y-247638D02*
X290233Y-245593D01*
X293445D01*
X289559Y-243593D02*
X293445D01*
X288057Y-245095D02*
X289559Y-243593D01*
X288166Y-241593D02*
X293445D01*
X287941Y-241819D02*
X288166Y-241593D01*
X288189Y-235827D02*
X288422Y-235593D01*
X293445D01*
X471654Y-292520D02*
X502869Y-323735D01*
X469291Y-292520D02*
X471654D01*
X502869Y-353233D02*
Y-323735D01*
X648425Y-336614D02*
Y-304724D01*
Y-336614D02*
X650394Y-338583D01*
X655118D01*
X626772Y-334252D02*
X631496Y-338976D01*
X637008D01*
X634252Y-290551D02*
X648425Y-304724D01*
X511811Y-290551D02*
X634252D01*
X431102Y-209842D02*
X511811Y-290551D01*
X368110Y-209842D02*
X431102D01*
X368504Y-213779D02*
X415748D01*
X626772Y-334252D02*
Y-305118D01*
X620079Y-298425D02*
X626772Y-305118D01*
X500394Y-298425D02*
X620079D01*
X415748Y-213779D02*
X500394Y-298425D01*
X528338Y-331738D02*
X532619D01*
X524056D02*
X528338D01*
X532619D02*
Y-328288D01*
X525591Y-321260D02*
X532619Y-328288D01*
X507480Y-321260D02*
X525591D01*
X400394Y-223622D02*
X469291Y-292520D01*
X369291Y-223622D02*
X400394D01*
X405905Y-219685D02*
X507480Y-321260D01*
X369685Y-219685D02*
X405905D01*
X358661Y-208661D02*
X369685Y-219685D01*
X362598Y-201181D02*
X367717Y-206299D01*
X358661Y-201181D02*
X358661Y-201181D01*
X362598D01*
X367717Y-206299D02*
X370079D01*
X358661Y-208661D02*
Y-201181D01*
X370079Y-206299D02*
Y-201969D01*
X364961Y-196850D02*
X370079Y-201969D01*
X355512Y-196850D02*
X364961D01*
X354739Y-197623D02*
X355512Y-196850D01*
X348876Y-197623D02*
X354739D01*
X355906Y-210236D02*
Y-198425D01*
X362598D02*
X366535Y-202362D01*
X355906Y-198425D02*
X362598D01*
X355906Y-210236D02*
X369291Y-223622D01*
X523958Y-347880D02*
X532225D01*
X532283Y-347938D01*
Y-353150D02*
Y-347938D01*
X528346Y-357087D02*
X532283Y-353150D01*
X506723Y-357087D02*
X528346D01*
X502869Y-353233D02*
X506723Y-357087D01*
X655118Y-329921D02*
X655709Y-329331D01*
X655118Y-338583D02*
Y-329921D01*
X637008Y-338976D02*
Y-329232D01*
X609291Y-350630D02*
Y-343543D01*
Y-350630D02*
X613779Y-355118D01*
X628740D01*
X637008Y-346850D01*
X642913Y-358661D02*
X655118Y-346457D01*
X593701Y-358661D02*
X642913D01*
X589291Y-354252D02*
X593701Y-358661D01*
X589291Y-354252D02*
Y-343543D01*
X540099Y-347880D02*
X549700Y-357480D01*
X576378D01*
X579291Y-354567D01*
Y-343543D01*
X540493Y-331738D02*
X552298Y-343543D01*
X569291D01*
X609291D02*
X609449Y-343701D01*
X589291Y-343543D02*
X589372Y-343624D01*
X579134Y-343701D02*
X579291Y-343543D01*
X116142Y-263632D02*
X121063D01*
X116142Y-263632D02*
X116142Y-263632D01*
X116142Y-308268D02*
Y-263632D01*
X95669Y-328740D02*
X116142Y-308268D01*
X95669Y-342126D02*
Y-328740D01*
Y-342126D02*
X103150Y-349606D01*
X164567D01*
X170866Y-355906D01*
Y-375197D02*
Y-355906D01*
Y-375197D02*
X175984Y-380315D01*
X184252D01*
X187156Y-377411D01*
X190354D01*
X603002Y-247441D02*
Y-243744D01*
X596702Y-247441D02*
Y-243878D01*
X602919Y-243661D02*
X603002Y-243744D01*
X596702Y-243878D02*
X596919Y-243661D01*
X576191Y-206890D02*
X580438D01*
X580738Y-207189D02*
X580954D01*
X580438Y-206890D02*
X580738Y-207189D01*
X531526Y-262617D02*
X536337D01*
X536367Y-262587D01*
X531496Y-262647D02*
X531526Y-262617D01*
X461417Y-316584D02*
Y-311289D01*
X461811Y-310895D01*
Y-310679D01*
X449606Y-300640D02*
Y-294360D01*
X450000Y-293966D02*
Y-293750D01*
X449606Y-294360D02*
X450000Y-293966D01*
X422047Y-300640D02*
Y-294399D01*
X422441Y-294005D01*
Y-293789D01*
X531526Y-213405D02*
X536338D01*
X536367Y-213375D01*
X531496Y-213435D02*
X531526Y-213405D01*
X520437Y-233074D02*
X525576D01*
X520423Y-233060D02*
X520437Y-233074D01*
X525576D02*
X525591Y-233088D01*
X439730Y-168479D02*
Y-162582D01*
Y-168479D02*
X439762Y-168512D01*
X439697Y-162549D02*
X439730Y-162582D01*
X420077Y-157114D02*
Y-152568D01*
Y-157114D02*
X420669Y-157706D01*
Y-157923D02*
Y-157706D01*
X531526Y-223247D02*
X536337D01*
X536367Y-223217D01*
X531496Y-223277D02*
X531526Y-223247D01*
X332932Y-235024D02*
X333024Y-235116D01*
X338462D01*
X338583Y-235236D01*
X520423Y-242902D02*
X520453Y-242932D01*
X525561D01*
X525591Y-242962D01*
X429920Y-168512D02*
Y-162699D01*
X430150Y-162470D01*
Y-162253D01*
X410235Y-157414D02*
Y-152568D01*
X410528Y-157923D02*
Y-157706D01*
X410235Y-157414D02*
X410528Y-157706D01*
X443700Y-300640D02*
Y-294360D01*
X444095Y-293966D02*
Y-293750D01*
X443700Y-294360D02*
X444095Y-293966D01*
X422047Y-316584D02*
Y-312076D01*
X422835Y-311289D01*
Y-311072D01*
X531510Y-233074D02*
X536353D01*
X536367Y-233060D01*
X531496Y-233088D02*
X531510Y-233074D01*
X430012Y-157786D02*
Y-152660D01*
X429920Y-152568D02*
X430012Y-152660D01*
Y-157786D02*
X430150Y-157923D01*
X402362Y-316584D02*
Y-311683D01*
X402756Y-311289D01*
Y-311072D01*
X520515Y-252837D02*
X524243D01*
X520423Y-252745D02*
X520515Y-252837D01*
X524243D02*
X525374Y-253969D01*
X525591D01*
X420078Y-168511D02*
Y-162549D01*
X420077Y-168512D02*
X420078Y-168511D01*
Y-162549D02*
X420079Y-162549D01*
X520423Y-203532D02*
X520453Y-203562D01*
X525561D01*
X525591Y-203592D01*
X400392Y-157727D02*
Y-152568D01*
X400295Y-157824D02*
X400392Y-157727D01*
X531526Y-242932D02*
X536337D01*
X536367Y-242902D01*
X531496Y-242962D02*
X531526Y-242932D01*
X402362Y-300640D02*
Y-293750D01*
X520454Y-262617D02*
X525560D01*
X520423Y-262587D02*
X520454Y-262617D01*
X525560D02*
X525591Y-262647D01*
X410235Y-168512D02*
Y-163652D01*
X410913Y-162974D01*
Y-162758D01*
X455511Y-300640D02*
Y-294754D01*
X456299Y-293966D01*
Y-293750D01*
X437795Y-300640D02*
Y-293750D01*
X437795Y-293750D02*
X437795Y-293750D01*
X520453Y-213405D02*
X525561D01*
X520423Y-213375D02*
X520453Y-213405D01*
X525561D02*
X525591Y-213435D01*
X459383Y-168448D02*
Y-162575D01*
Y-168448D02*
X459447Y-168512D01*
X459319Y-162510D02*
X459383Y-162575D01*
Y-157858D02*
Y-152632D01*
X459447Y-152568D01*
X459319Y-157922D02*
X459383Y-157858D01*
X412204Y-316584D02*
Y-311683D01*
X412598Y-311289D02*
Y-311072D01*
X412204Y-311683D02*
X412598Y-311289D01*
X532844Y-252837D02*
X536275D01*
X536367Y-252745D01*
X531713Y-253969D02*
X532844Y-252837D01*
X531496Y-253969D02*
X531713D01*
X449697Y-157817D02*
Y-152660D01*
X449605Y-152568D02*
X449697Y-152660D01*
Y-157817D02*
X449803Y-157923D01*
X536337Y-203562D02*
X536367Y-203532D01*
X531526Y-203562D02*
X536337D01*
X531496Y-203592D02*
X531526Y-203562D01*
X400392Y-168512D02*
Y-163613D01*
X401279Y-162726D01*
Y-162509D01*
X439854Y-157817D02*
Y-152660D01*
X439762Y-152568D02*
X439854Y-152660D01*
Y-157817D02*
X439961Y-157923D01*
X461417Y-300640D02*
Y-293750D01*
X520453Y-223247D02*
X525561D01*
X520423Y-223217D02*
X520453Y-223247D01*
X525561D02*
X525591Y-223277D01*
X449513Y-168420D02*
Y-165540D01*
X449508Y-165534D02*
X449513Y-165540D01*
X449508Y-165534D02*
Y-162549D01*
X449513Y-168420D02*
X449605Y-168512D01*
X343624Y-235116D02*
X348784D01*
X348876Y-235024D01*
X343504Y-235236D02*
X343624Y-235116D01*
X412204Y-300640D02*
X412205Y-300640D01*
Y-293750D01*
X412205Y-293750D01*
X269685Y-136843D02*
X269838Y-136689D01*
Y-132573D01*
X232894Y-129399D02*
X234252Y-130757D01*
Y-133742D02*
Y-130757D01*
X263779Y-111860D02*
Y-106151D01*
X83661Y-315945D02*
X85630Y-313976D01*
X81004Y-315945D02*
X83661D01*
X85630Y-260827D02*
Y-260059D01*
X86614Y-259075D02*
Y-258858D01*
X85630Y-260059D02*
X86614Y-259075D01*
X84646Y-261811D02*
X85630Y-260827D01*
X81988Y-261811D02*
X84646D01*
Y-205709D02*
X85630Y-206693D01*
X81693Y-205709D02*
X84646D01*
X85630Y-208661D02*
Y-206693D01*
X84646Y-209646D02*
X85630Y-208661D01*
X81988Y-209646D02*
X84646D01*
X76986Y-109843D02*
X82677D01*
X75845Y-110984D02*
X76986Y-109843D01*
X86004D02*
X86398Y-110236D01*
X82677Y-109843D02*
X86004D01*
X86398Y-110236D02*
X86614D01*
X360171Y-268521D02*
X360236Y-268586D01*
X348908Y-268521D02*
X360171D01*
X348876Y-268489D02*
X348908Y-268521D01*
Y-272458D02*
X360204D01*
X360236Y-272490D01*
X348876Y-272426D02*
X348908Y-272458D01*
X26495Y-8991D02*
Y-4705D01*
X26575Y-4626D01*
X68701Y-227362D02*
X68898Y-227165D01*
X63976Y-227362D02*
X68701D01*
X68898Y-285433D02*
Y-281299D01*
X67913Y-340551D02*
Y-335433D01*
Y-178444D02*
X68573Y-179104D01*
Y-179321D02*
Y-179104D01*
X67913Y-178444D02*
Y-175000D01*
X44291Y-326772D02*
Y-322736D01*
Y-311122D02*
Y-307087D01*
X27185Y-291732D02*
X31496D01*
X26791Y-291339D02*
X27185Y-291732D01*
X26575Y-291339D02*
X26791D01*
X31496Y-189961D02*
Y-184055D01*
X44291Y-151673D02*
Y-147638D01*
Y-167323D02*
Y-163287D01*
Y-204823D02*
Y-200787D01*
Y-220472D02*
Y-216437D01*
Y-272638D02*
Y-268602D01*
Y-256988D02*
Y-252953D01*
X326311Y-242898D02*
X332932D01*
X326004Y-243205D02*
X326311Y-242898D01*
X325787Y-243205D02*
X326004D01*
X326310Y-233056D02*
X332932D01*
X326004Y-233362D02*
X326310Y-233056D01*
X325787Y-233362D02*
X326004D01*
X103409Y-141732D02*
Y-138935D01*
X103347Y-116831D02*
Y-110236D01*
X116298Y-126047D02*
X119095D01*
X116235Y-125984D02*
X116298Y-126047D01*
X112500Y-125984D02*
X116235D01*
X103347Y-138872D02*
Y-135138D01*
Y-138872D02*
X103409Y-138935D01*
X487205Y-137647D02*
X494095D01*
X518701Y-115994D02*
Y-104214D01*
X513681Y-128691D02*
X519685Y-134695D01*
X528543Y-112057D02*
Y-104214D01*
X649390Y-21899D02*
X658465D01*
X625000Y-29773D02*
X631890D01*
X114173Y-83088D02*
Y-79379D01*
X441929Y-122883D02*
X447638D01*
X273465Y-128946D02*
X279528D01*
X269838Y-132573D02*
X273465Y-128946D01*
X258858Y-126821D02*
X262205D01*
X256890Y-124852D02*
X258858Y-126821D01*
X256890Y-121899D02*
X259842Y-118947D01*
X262205D01*
X263779Y-111860D02*
X263976Y-112057D01*
X227756Y-129399D02*
X232894D01*
X244291Y-120915D02*
X250000D01*
X244094Y-120718D02*
X244291Y-120915D01*
X447638Y-122883D02*
X448622Y-123868D01*
X451772D01*
X486128Y-128746D02*
X486221Y-128838D01*
X486128Y-128746D02*
Y-127197D01*
X484768Y-125836D02*
X486128Y-127197D01*
X481250Y-125836D02*
X484768D01*
X487205Y-137647D02*
X488189Y-136663D01*
Y-128838D01*
X124606Y-79576D02*
X129921D01*
X123819Y-78789D02*
X124606Y-79576D01*
X451772Y-123868D02*
X453740Y-125836D01*
X459646D01*
X460630Y-124852D01*
Y-121639D01*
X473425Y-125836D02*
X481250D01*
X473425Y-123868D02*
X481250D01*
X473425Y-121899D02*
X481250D01*
X500000Y-137647D02*
X505905D01*
X511713Y-128691D02*
X513681D01*
X519685Y-120915D02*
X519783Y-121013D01*
X515748Y-120915D02*
X519685D01*
X512002Y-123284D02*
X513379D01*
X515748Y-120915D01*
X511713Y-123572D02*
X512002Y-123284D01*
X519783Y-121013D02*
Y-117076D01*
X518701Y-115994D02*
X519783Y-117076D01*
X614321Y-118307D02*
X618298D01*
X91536Y-50049D02*
X99410D01*
X67913Y-281299D02*
X68110Y-281496D01*
X512658Y-270462D02*
X520423D01*
X512657Y-270462D02*
X512658Y-270462D01*
X520423D02*
X520423Y-270461D01*
X560919Y-253555D02*
Y-243150D01*
X565919Y-226417D02*
Y-223661D01*
X560431Y-231906D02*
X565919Y-226417D01*
X560919Y-223661D02*
Y-223277D01*
X560197Y-222555D02*
X560919Y-223277D01*
X555135Y-231906D02*
X560431D01*
X554419Y-222555D02*
X560197D01*
X582135Y-228689D02*
X582419D01*
X576573Y-228689D02*
X582135Y-228689D01*
X575919Y-228035D02*
Y-226417D01*
Y-228035D02*
X576573Y-228689D01*
X577545Y-217189D02*
X582419D01*
X575919Y-218815D02*
X577545Y-217189D01*
X575919Y-223661D02*
X575919Y-226417D01*
X575836Y-213146D02*
X576076Y-212906D01*
X575919Y-226417D02*
Y-223661D01*
Y-218815D01*
X575836Y-215945D02*
Y-213146D01*
X574655Y-217126D02*
X575836Y-215945D01*
X571899Y-217126D02*
X574655D01*
X570919Y-218106D02*
X571899Y-217126D01*
X570919Y-213713D02*
X571726Y-212906D01*
X570919Y-223661D02*
Y-218106D01*
X570761Y-212906D02*
Y-206894D01*
X570757Y-206890D02*
X570761Y-206894D01*
X618013Y-274905D02*
X618356Y-275248D01*
X536397Y-199625D02*
X544261D01*
X536367Y-199595D02*
X536397Y-199625D01*
X544261D02*
X544291Y-199655D01*
X509872Y-197657D02*
X520394D01*
X520423Y-197627D01*
X509842Y-197687D02*
X509872Y-197657D01*
X536397Y-201594D02*
X544262D01*
X536367Y-201564D02*
X536397Y-201594D01*
X544262D02*
X544291Y-201624D01*
X509873Y-199625D02*
X520393D01*
X520423Y-199595D01*
X509842Y-199655D02*
X509873Y-199625D01*
X509872Y-201594D02*
X520394D01*
X520423Y-201564D01*
X509842Y-201624D02*
X509872Y-201594D01*
X348908Y-250766D02*
X348915Y-250758D01*
X536397Y-197657D02*
X544262D01*
X536367Y-197627D02*
X536397Y-197657D01*
X544262D02*
X544291Y-197687D01*
X509873Y-195688D02*
X520393D01*
X520423Y-195658D01*
X509842Y-195718D02*
X509873Y-195688D01*
X361811Y-207087D02*
X368504Y-213779D01*
X361417Y-203150D02*
X368110Y-209842D01*
X346503Y-195640D02*
X354776D01*
X355928Y-194488D01*
X358661D01*
X199898Y-119399D02*
X209252D01*
X199311Y-119931D02*
X199803Y-119439D01*
X237555Y-133311D02*
Y-132524D01*
X237402Y-133465D02*
X237555Y-133311D01*
Y-132524D02*
X239201Y-130877D01*
X248031Y-130137D02*
Y-127165D01*
X247291Y-130877D02*
X248031Y-130137D01*
X239201Y-130877D02*
X247291D01*
X241387Y-125639D02*
X242520Y-126772D01*
X237205Y-125639D02*
X241387D01*
X242520Y-127165D02*
Y-126772D01*
X265706Y-132277D02*
X267286Y-130697D01*
X262806Y-132277D02*
X265706D01*
X326966Y-195171D02*
X327183D01*
X327666Y-195654D01*
X267305Y-126839D02*
X267323Y-126821D01*
X267305Y-130679D02*
Y-126839D01*
X267286Y-130697D02*
X267305Y-130679D01*
X105362Y-140064D02*
Y-135185D01*
X101394Y-140095D02*
X101409Y-140111D01*
X109331Y-140032D02*
Y-135216D01*
X97409Y-140111D02*
X97425Y-140095D01*
X105362Y-140064D02*
X105409Y-140111D01*
X109331Y-140032D02*
X109409Y-140111D01*
X101394Y-140095D02*
Y-135153D01*
X97425Y-140095D02*
Y-135153D01*
X399618Y-136828D02*
Y-134706D01*
X399606Y-134695D02*
X399618Y-134706D01*
X65945Y-57923D02*
X74036D01*
X615158Y-9075D02*
Y-8858D01*
X615522Y-14017D02*
Y-9440D01*
X615158Y-9075D02*
X615522Y-9440D01*
X348945Y-252757D02*
X357804D01*
X358032Y-252984D01*
X360204D01*
X221850Y-354478D02*
X276969D01*
X178543Y-377411D02*
X181644D01*
X204577Y-354478D02*
X221850D01*
X181644Y-377411D02*
X204577Y-354478D01*
X354634Y-229027D02*
X356425Y-227237D01*
Y-225400D02*
X356578Y-225247D01*
X356425Y-227237D02*
Y-225400D01*
X354541Y-225672D02*
Y-223636D01*
X353709Y-236993D02*
X354299Y-236403D01*
X354178Y-226036D02*
X354541Y-225672D01*
X354299Y-235389D02*
X354452Y-235236D01*
X354299Y-236403D02*
Y-235389D01*
X354178Y-226531D02*
Y-226036D01*
X326993Y-197598D02*
X332908D01*
X326969Y-197573D02*
X326993Y-197598D01*
X327666Y-195654D02*
X332932D01*
X332908Y-197598D02*
X332932Y-197623D01*
X82677Y-169291D02*
X86614D01*
X361499Y-236802D02*
Y-235358D01*
X361652Y-235205D01*
X79724Y-168307D02*
X82677D01*
X359131Y-226369D02*
Y-223425D01*
X361531Y-225808D02*
Y-223425D01*
X348876Y-233056D02*
X354282D01*
X361531Y-225808D01*
X354413Y-231087D02*
X359131Y-226369D01*
X38287Y-157480D02*
X54331D01*
X359623Y-262583D02*
X360020Y-262186D01*
X348876Y-262583D02*
X359623D01*
X360020Y-262186D02*
X360236D01*
X358499Y-266032D02*
X358500Y-266033D01*
X360083D01*
X360236Y-266186D01*
X357836Y-266032D02*
X358499D01*
X357348Y-266520D02*
X357836Y-266032D01*
X348876Y-266520D02*
X357348D01*
X81111Y-317806D02*
X85309D01*
X81004Y-317913D02*
X81111Y-317806D01*
X85309D02*
X85416Y-317699D01*
X81988Y-263779D02*
X85630D01*
X86409Y-211336D02*
X86562Y-211183D01*
X81988Y-211614D02*
X84861D01*
X85140Y-211336D02*
X86409D01*
X84861Y-211614D02*
X85140Y-211336D01*
X411196Y-174821D02*
Y-173804D01*
X411043Y-174974D02*
X411196Y-174821D01*
X416142Y-173742D02*
Y-168513D01*
X413440Y-174850D02*
Y-174634D01*
X411196Y-173804D02*
X412203Y-172797D01*
X416142Y-173742D02*
X417596Y-175197D01*
X413440Y-174634D02*
X414172Y-173901D01*
X421443Y-174881D02*
X421596Y-175034D01*
X420262Y-174881D02*
X421443D01*
X418109Y-172728D02*
X420262Y-174881D01*
X414172Y-173901D02*
Y-168512D01*
X406528Y-157767D02*
Y-157550D01*
X406298Y-157321D02*
Y-152568D01*
Y-157321D02*
X406528Y-157550D01*
X408266Y-156677D02*
Y-152568D01*
X408528Y-159169D02*
Y-156938D01*
X408266Y-156677D02*
X408528Y-156938D01*
X407480Y-160217D02*
X408528Y-159169D01*
X404528Y-163386D02*
X406206Y-165065D01*
Y-168420D02*
Y-165065D01*
X407480Y-160433D02*
Y-160217D01*
X418109Y-172728D02*
Y-168512D01*
X412203Y-172797D02*
Y-168512D01*
X82677Y-221457D02*
X86614D01*
X428043Y-172580D02*
X430807Y-175344D01*
X427165Y-175246D02*
Y-175029D01*
X425983Y-173847D02*
X427165Y-175029D01*
X428043Y-172580D02*
Y-168604D01*
X89567Y-166370D02*
Y-161418D01*
X86614Y-158465D02*
X89567Y-161418D01*
X81004Y-158465D02*
X86614D01*
X87167Y-166377D02*
Y-162955D01*
X81004Y-160433D02*
X84646D01*
X87167Y-162955D01*
X81988Y-213583D02*
X85630D01*
X85630Y-213583D01*
X81988Y-265748D02*
X84982D01*
X85413Y-266179D01*
X85630D01*
X85413Y-320313D02*
X85630D01*
X81004Y-319882D02*
X84982D01*
X85413Y-320313D01*
X536367Y-236997D02*
X540562D01*
X544291Y-233268D01*
X542496Y-227154D02*
X543059Y-226591D01*
X536367Y-227154D02*
X542496D01*
X543059Y-226591D02*
X543276D01*
X536367Y-225186D02*
X541079D01*
X542017Y-224248D01*
X544294D01*
X348876Y-236993D02*
X353709D01*
X356852Y-237636D02*
Y-235236D01*
X355527Y-238961D02*
X356852Y-237636D01*
X355403Y-242898D02*
X361499Y-236802D01*
X359099Y-235389D02*
X359252Y-235236D01*
X359099Y-237228D02*
Y-235389D01*
X355397Y-240930D02*
X359099Y-237228D01*
X348876Y-240930D02*
X355397D01*
X348876Y-238961D02*
X355527D01*
X348876Y-242898D02*
X355403D01*
X353559Y-227150D02*
X354178Y-226531D01*
X348876Y-227150D02*
X348876Y-227150D01*
X353559D01*
X348968Y-229027D02*
X354634D01*
X348876Y-231087D02*
X354413D01*
X348876Y-229119D02*
X348968Y-229027D01*
X406206Y-168420D02*
X406298Y-168512D01*
X407480Y-163475D02*
X408266Y-164261D01*
Y-168512D02*
Y-164261D01*
X407480Y-163475D02*
Y-163386D01*
X33465Y-8858D02*
Y-4626D01*
X40354Y-8858D02*
Y-4626D01*
X47244Y-8858D02*
Y-4626D01*
Y14764D02*
Y19685D01*
X40354Y14764D02*
Y19685D01*
X26575Y14764D02*
Y19685D01*
X33465Y14764D02*
Y19833D01*
X47244Y689D02*
Y8858D01*
X40354Y689D02*
Y8858D01*
X33465Y689D02*
Y8858D01*
X26575Y689D02*
Y8858D01*
X80709Y-232283D02*
X82677D01*
X79232Y-230807D02*
Y-221949D01*
Y-230807D02*
X80709Y-232283D01*
X75787Y-221457D02*
X78740D01*
X79232Y-221949D01*
X83661Y-275590D02*
X87598D01*
X79724Y-285433D02*
X81693Y-287402D01*
X79724Y-285433D02*
Y-276575D01*
X75787Y-275590D02*
X78740D01*
X79724Y-276575D01*
X78740Y-340551D02*
Y-330193D01*
X78272Y-329724D02*
X78740Y-330193D01*
X74803Y-329724D02*
X78272D01*
X80266Y-328298D02*
X81207D01*
X77756Y-325787D02*
X80266Y-328298D01*
X77756Y-325787D02*
Y-322835D01*
X81207Y-328298D02*
X81568Y-328659D01*
Y-329600D02*
Y-328659D01*
X86614Y-169291D02*
X86614Y-169291D01*
X74803Y-169488D02*
X75000Y-169291D01*
X78740Y-178150D02*
X80709Y-180118D01*
X78740Y-178150D02*
Y-170276D01*
X77756Y-169291D02*
X78740Y-170276D01*
X74803Y-169291D02*
X77756D01*
X80813Y-322041D02*
X81004Y-321850D01*
X78550Y-322041D02*
X80813D01*
X77756Y-322835D02*
X78550Y-322041D01*
X68602Y-319882D02*
X73819D01*
X74803Y-329724D02*
Y-320866D01*
X73819Y-319882D02*
X74803Y-320866D01*
X78740Y-271654D02*
X82677Y-275590D01*
X78740Y-271654D02*
Y-268701D01*
X81798Y-267907D02*
X81988Y-267717D01*
X79534Y-267907D02*
X81798D01*
X78740Y-268701D02*
X79534Y-267907D01*
X75787Y-275590D02*
Y-266732D01*
X69587Y-265748D02*
X74803D01*
X75787Y-266732D01*
X38139Y-316781D02*
X38189Y-316831D01*
Y-291732D01*
Y-316831D02*
X38287Y-316929D01*
X38189Y-263630D02*
Y-262894D01*
Y-283071D02*
Y-263630D01*
X38780Y-263287D02*
X39272Y-262795D01*
X-8465Y-263630D02*
X38189D01*
Y-262894D02*
X38287Y-262795D01*
X39272D02*
X55315D01*
X78740Y-218504D02*
X81693Y-221457D01*
X78740Y-216020D02*
X79209Y-215551D01*
X81988D01*
X78740Y-218504D02*
Y-216020D01*
X69587Y-213583D02*
X69587Y-213583D01*
X73819D01*
X75787Y-215551D01*
Y-221457D02*
Y-215551D01*
X38138Y-210480D02*
X38189Y-210429D01*
X38138Y-210480D02*
X38287Y-210630D01*
X55315D01*
X38189Y-210429D02*
Y-184055D01*
Y-175394D02*
X38287Y-175295D01*
Y-157480D01*
X80955Y-162450D02*
X81004Y-162402D01*
X77756Y-163386D02*
X78692Y-162450D01*
X80955D01*
X77756Y-166339D02*
Y-163386D01*
Y-166339D02*
X79724Y-168307D01*
X68602Y-160433D02*
X72835D01*
X74803Y-169291D02*
Y-162402D01*
X72835Y-160433D02*
X74803Y-162402D01*
X65945Y-158465D02*
X68602D01*
X64961Y-157480D02*
X65945Y-158465D01*
X64961Y-157480D02*
X65945Y-156496D01*
X68602D01*
X59842Y-157480D02*
X64961D01*
X66929Y-209646D02*
X69587D01*
X65945Y-210630D02*
X66929Y-209646D01*
X65945Y-210630D02*
X66929Y-211614D01*
X60827Y-210630D02*
X65945D01*
X66929Y-211614D02*
X69587D01*
X65729Y-262795D02*
X66713Y-263779D01*
X69587D01*
X66713Y-261811D02*
X69587D01*
X65729Y-262795D02*
X66713Y-261811D01*
X60827Y-262795D02*
X65729D01*
X64961Y-316929D02*
X65945Y-317913D01*
X68602D01*
X65945Y-315945D02*
X68602D01*
X64961Y-316929D02*
X65945Y-315945D01*
X59646Y-316929D02*
X64961D01*
X38287D02*
X54134D01*
X-8465Y-316781D02*
X38139D01*
X-8465Y-210480D02*
X38138D01*
X38139Y-157332D02*
X38287Y-157480D01*
X-8465Y-157332D02*
X38139D01*
X323850Y-241173D02*
X323882Y-241205D01*
X327144D01*
X323850Y-237205D02*
X327175D01*
X323819Y-227362D02*
X327175D01*
X328387Y-229119D02*
X332932D01*
X327418Y-231087D02*
X332932D01*
X328144Y-229362D02*
X328387Y-229119D01*
X327143Y-231362D02*
X327418Y-231087D01*
X323819Y-231299D02*
X323882Y-231362D01*
X325787Y-229362D02*
X328144D01*
X323882Y-231362D02*
X327143D01*
X327418Y-240930D02*
X332932D01*
X327144Y-241205D02*
X327418Y-240930D01*
X328387Y-238961D02*
X332932D01*
X328143Y-239205D02*
X328387Y-238961D01*
X325787Y-239205D02*
X328143D01*
X327387Y-236993D02*
X332932D01*
X327175Y-237205D02*
X327387Y-236993D01*
X327175Y-227362D02*
X327387Y-227150D01*
X332932D01*
X-20122Y-342673D02*
X-19685Y-343110D01*
X-23469Y-342673D02*
X-20122D01*
X-23622Y-342520D02*
X-23469Y-342673D01*
X101378Y-135138D02*
X101394Y-135153D01*
X87254Y-133218D02*
X90551Y-129921D01*
X87254Y-139629D02*
Y-133218D01*
X89567Y-140270D02*
Y-132874D01*
X112579Y-131968D02*
X117047D01*
X112500Y-131890D02*
X112579Y-131968D01*
X116298Y-130047D02*
X119095D01*
X117047Y-131968D02*
X117126Y-132047D01*
X105331Y-112221D02*
X105347Y-112205D01*
X105331Y-116815D02*
Y-112221D01*
X107346Y-116768D02*
Y-110236D01*
X99283Y-113033D02*
Y-110299D01*
X99347Y-110236D01*
X109331Y-116752D02*
Y-112315D01*
X109409Y-112236D01*
X112501Y-122047D02*
X119095D01*
X112500Y-122047D02*
X112501Y-122047D01*
X-23622Y-290354D02*
X-19685D01*
X-23469Y-286570D02*
X-19926D01*
X-19685Y-286811D01*
X-23622Y-286417D02*
X-23469Y-286570D01*
Y-282633D02*
X-18843D01*
X-23622Y-282480D02*
X-23469Y-282633D01*
X-18843D02*
X-18406Y-283071D01*
X-23469Y-237052D02*
X-19926D01*
X-23622Y-237205D02*
X-23469Y-237052D01*
X-19926D02*
X-19685Y-236811D01*
X-23622Y-233268D02*
X-19685D01*
X-23622Y-229331D02*
X-23524Y-229429D01*
X-18504D02*
X-18406Y-229528D01*
X-23524Y-229429D02*
X-18504D01*
X-23622Y-339567D02*
X-19685D01*
X-23622Y-335630D02*
X-23524Y-335728D01*
X-18504D02*
X-18406Y-335827D01*
X-23524Y-335728D02*
X-18504D01*
X109252Y-116831D02*
X109331Y-116752D01*
X107409Y-141732D02*
Y-138935D01*
X99410Y-141732D02*
Y-135138D01*
X-23622Y-184055D02*
X-19685D01*
X-23622Y-181102D02*
X-23469Y-180949D01*
X-20122D02*
X-19685Y-180512D01*
X-23469Y-180949D02*
X-20122D01*
X-23469Y-177012D02*
X-18646D01*
X-18406Y-176772D01*
X-23622Y-177165D02*
X-23469Y-177012D01*
X-23622Y-110236D02*
X-19685D01*
X-23469Y-106452D02*
X-19926D01*
X-19685Y-106693D01*
X-23622Y-106299D02*
X-23469Y-106452D01*
X-18843Y-102515D02*
X-18406Y-102953D01*
X-23469Y-102515D02*
X-18843D01*
X-23622Y-102362D02*
X-23469Y-102515D01*
X-23622Y-66929D02*
X-19685D01*
X-23469Y-63145D02*
X-19926D01*
X-19685Y-63386D01*
X-23622Y-62992D02*
X-23469Y-63145D01*
Y-59886D02*
X-18646D01*
X-23622Y-60039D02*
X-23469Y-59886D01*
X-18646D02*
X-18406Y-59646D01*
X116172Y-129921D02*
X116298Y-130047D01*
X117111Y-124031D02*
X117126Y-124047D01*
X112500Y-129921D02*
X116172D01*
X117079Y-128000D02*
X117126Y-128047D01*
X112547Y-128000D02*
X117079D01*
X112500Y-127953D02*
X112547Y-128000D01*
X112515Y-124031D02*
X117111D01*
X112500Y-124016D02*
X112515Y-124031D01*
X112579Y-120000D02*
X117047D01*
X112500Y-120079D02*
X112579Y-120000D01*
X117047D02*
X117126Y-119921D01*
X99283Y-113033D02*
X99410Y-113159D01*
Y-116831D02*
Y-113159D01*
X107283Y-116831D02*
X107346Y-116768D01*
X105315Y-116831D02*
X105331Y-116815D01*
X97284Y-112205D02*
X97362Y-112284D01*
X101284Y-112205D02*
X101331Y-112252D01*
X97362Y-116752D02*
Y-112284D01*
X101331Y-116783D02*
X101378Y-116831D01*
X97362Y-116752D02*
X97441Y-116831D01*
X101331Y-116783D02*
Y-112252D01*
X109252Y-135138D02*
X109331Y-135216D01*
X107283Y-138809D02*
Y-135138D01*
Y-138809D02*
X107409Y-138935D01*
X105315Y-135138D02*
X105362Y-135185D01*
X97425Y-135153D02*
X97441Y-135138D01*
X89567Y-132874D02*
X90551Y-131890D01*
X94193D01*
X90551Y-129921D02*
X94193D01*
X86614Y-123031D02*
X87598Y-122047D01*
X94193D01*
X615530Y-14025D02*
X617126Y-15621D01*
X615522Y-14017D02*
X615530Y-14025D01*
X631890D01*
X617126Y-21506D02*
Y-15621D01*
X544261Y-195688D02*
X544291Y-195718D01*
X536397Y-195688D02*
X544261D01*
X536367Y-195658D02*
X536397Y-195688D01*
X528691Y-117716D02*
X533878D01*
X524459Y-125984D02*
X524606Y-125836D01*
X519808Y-128715D02*
X524533D01*
X519931Y-125984D02*
X524459D01*
X524533Y-128715D02*
X524557Y-128740D01*
X450850Y-174127D02*
Y-173910D01*
X451573Y-173187D01*
Y-168512D01*
X519783Y-123572D02*
X527264D01*
X528445Y-122391D02*
Y-117667D01*
X516634Y-123572D02*
X519783D01*
X527264D02*
X528445Y-122391D01*
X512795Y-111663D02*
X513189Y-112057D01*
X512795Y-111663D02*
Y-104214D01*
Y-104183D01*
X320898Y-272458D02*
X332901D01*
X320866Y-272490D02*
X320898Y-272458D01*
X332901D02*
X332932Y-272426D01*
X463551Y-116210D02*
X464370Y-117029D01*
X463551Y-116210D02*
Y-116025D01*
X649390Y-37647D02*
X658465D01*
X649390Y-29773D02*
X658465D01*
X625000Y-21899D02*
X631890D01*
X412339Y-123805D02*
X412339D01*
X417126Y-128592D01*
X424106Y-175139D02*
Y-168604D01*
Y-175139D02*
X424213Y-175246D01*
X424014Y-168512D02*
X424106Y-168604D01*
X298425Y-118947D02*
X314961D01*
X298484Y-128887D02*
X306616D01*
X306844Y-128659D01*
X309016D01*
X418898Y-144360D02*
Y-144143D01*
X418109Y-145148D02*
X418898Y-144360D01*
X418109Y-152568D02*
Y-145148D01*
X416106Y-144180D02*
X416123Y-144197D01*
X398424Y-152568D02*
Y-145227D01*
X398568Y-145083D01*
X416123Y-152551D02*
X416140Y-152568D01*
X519783Y-128691D02*
X519808Y-128715D01*
X491142Y-114911D02*
X492319D01*
X59842Y-157480D02*
X60236Y-157874D01*
X74803Y-170472D02*
Y-170466D01*
X447835Y-132726D02*
Y-128592D01*
Y-132726D02*
X452756Y-137647D01*
X456398D01*
X456890Y-137155D02*
Y-130034D01*
X456398Y-137647D02*
X456890Y-137155D01*
X492319Y-114970D02*
Y-114911D01*
X475295Y-133612D02*
X475394Y-133710D01*
Y-134695D02*
Y-133710D01*
X478346Y-137647D02*
X481693D01*
X475394Y-134695D02*
X478346Y-137647D01*
X500000Y-132135D02*
X500394Y-131742D01*
X505905D01*
X495079Y-130265D02*
X496949Y-132135D01*
X500000D01*
X528543Y-117569D02*
X528691Y-117716D01*
X528445Y-117667D02*
X528543Y-117569D01*
X513189Y-117667D02*
Y-112057D01*
X417126Y-128592D02*
X447835D01*
X443699Y-174634D02*
Y-168512D01*
X443898Y-175049D02*
Y-174832D01*
X443699Y-174634D02*
X443898Y-174832D01*
X91536Y-57923D02*
X99410D01*
X91536Y-65797D02*
X99410D01*
X65945Y-50049D02*
X74036D01*
X65945Y-65797D02*
X74036D01*
X484252Y-120866D02*
Y-115009D01*
X483268Y-114025D02*
X484252Y-115009D01*
X464370Y-121639D02*
Y-117029D01*
X488189Y-117864D02*
X491142Y-114911D01*
X487205Y-114242D02*
Y-114057D01*
X486221Y-115226D02*
X487205Y-114242D01*
X519783Y-126131D02*
X519931Y-125984D01*
X456742Y-116043D02*
X456816Y-116117D01*
Y-121565D02*
X456890Y-121639D01*
X456816Y-121565D02*
Y-116117D01*
X486221Y-120866D02*
Y-115226D01*
X488189Y-120866D02*
Y-117864D01*
X484252Y-120866D02*
X484252Y-120866D01*
X464328Y-146613D02*
Y-146397D01*
X463384Y-147557D02*
X464328Y-146613D01*
X463384Y-152568D02*
Y-147557D01*
X469291Y-143849D02*
X469291Y-143848D01*
X461368Y-152519D02*
Y-143798D01*
X469291Y-152568D02*
Y-143849D01*
X461319Y-143750D02*
X461368Y-143798D01*
X460925Y-137647D02*
X461024Y-137746D01*
X463189Y-137647D02*
X469488D01*
X460925D02*
X463189D01*
X267323Y-122883D02*
Y-118947D01*
X279528D01*
X267323Y-122883D02*
X267323Y-122883D01*
X469340Y-175098D02*
X469390Y-175147D01*
X457283D02*
X457387Y-175043D01*
X469340Y-175098D02*
Y-168562D01*
X457387Y-175043D02*
Y-168604D01*
X469290Y-168512D02*
X469340Y-168562D01*
X425983Y-173847D02*
Y-168512D01*
X402313Y-175295D02*
Y-168561D01*
X402361Y-168512D01*
X402264Y-175344D02*
X402313Y-175295D01*
X461368Y-152519D02*
X461416Y-152568D01*
X536397Y-215373D02*
X544261D01*
X544291Y-215403D01*
X536367Y-215343D02*
X536397Y-215373D01*
X514075Y-126131D02*
X516634Y-123572D01*
X511713Y-126131D02*
X514075D01*
X511713Y-121013D02*
X511811Y-120915D01*
Y-119045D01*
X513189Y-117667D01*
X491191Y-127805D02*
X491283Y-127897D01*
X493596D01*
X495079Y-129379D01*
Y-130265D02*
Y-129379D01*
X481693Y-137647D02*
Y-134104D01*
X484252Y-131545D02*
Y-128838D01*
X481693Y-134104D02*
X484252Y-131545D01*
X464370Y-136466D02*
Y-130034D01*
X463189Y-137647D02*
X464370Y-136466D01*
X512402Y-261958D02*
X514999Y-264556D01*
X520423D01*
X513818Y-266524D02*
X520423D01*
X512402Y-265108D02*
X513818Y-266524D01*
X512759Y-268065D02*
X513187Y-268493D01*
X512543Y-268065D02*
X512759D01*
X513187Y-268493D02*
X520423D01*
X457387Y-168604D02*
X457479Y-168512D01*
X437746Y-168561D02*
X437794Y-168512D01*
X437746Y-175197D02*
Y-168561D01*
X437697Y-175246D02*
X437746Y-175197D01*
X433858Y-175245D02*
Y-168512D01*
X433857Y-168512D02*
X433858Y-168512D01*
Y-175245D02*
X433858Y-175246D01*
X427951Y-168512D02*
X428043Y-168604D01*
X416140Y-168512D02*
X416142Y-168513D01*
X404329Y-174634D02*
Y-168512D01*
Y-174634D02*
X404823Y-175128D01*
Y-175344D02*
Y-175128D01*
X469290Y-152568D02*
X469291Y-152568D01*
X237008Y-125836D02*
X237205Y-125639D01*
X237008Y-129576D02*
Y-125836D01*
X267323Y-126821D02*
X271260D01*
X274134Y-123946D01*
X279528D01*
X298465Y-113986D02*
X309016D01*
X309055Y-114025D01*
X233268Y-119931D02*
X237008D01*
X237205Y-120127D01*
X232736Y-119399D02*
X233268Y-119931D01*
X227756Y-119399D02*
X232736D01*
X199311Y-115009D02*
X199803Y-114517D01*
X200088Y-114399D02*
X209252D01*
X193898Y-115009D02*
X199311D01*
X193898Y-119931D02*
X199311D01*
X298425Y-128946D02*
X298484Y-128887D01*
X298465Y-123907D02*
X309016D01*
X309055Y-123868D01*
X298425Y-123946D02*
X298465Y-123907D01*
X298425Y-113946D02*
X298465Y-113986D01*
X348915Y-252727D02*
X348945Y-252757D01*
X544813Y-120555D02*
X551707D01*
X572813Y-136189D02*
Y-129417D01*
X561156Y-105370D02*
X561211Y-105315D01*
X561156Y-111406D02*
Y-105370D01*
X566290Y-113976D02*
Y-111587D01*
X566471Y-111406D01*
X565502Y-114764D02*
X566290Y-113976D01*
X562746Y-114764D02*
X565502D01*
X561813Y-115697D02*
X562746Y-114764D01*
X561813Y-120661D02*
Y-115697D01*
X276969Y-399280D02*
Y-357824D01*
Y-399280D02*
X277165Y-399477D01*
X222047Y-401427D02*
X222244Y-401230D01*
Y-388041D01*
X225394Y-384891D02*
Y-372293D01*
X222244Y-388041D02*
X225394Y-384891D01*
X221850Y-368750D02*
X225394Y-372293D01*
X221850Y-368750D02*
Y-357824D01*
X277244Y-402150D02*
X277441Y-401953D01*
X276771Y-358021D02*
X276969Y-357824D01*
X546030Y-128405D02*
X551825D01*
X556813Y-123417D01*
Y-120661D01*
X571097Y-117757D02*
Y-117206D01*
X570080Y-118774D02*
X571097Y-117757D01*
X569528Y-118774D02*
X570080D01*
X568667Y-119636D02*
X569528Y-118774D01*
X567535Y-119636D02*
X568667D01*
X566813Y-120358D02*
X567535Y-119636D01*
X566813Y-120661D02*
Y-120358D01*
Y-123417D02*
Y-120661D01*
Y-123417D02*
X572813Y-129417D01*
X560919Y-253555D02*
X562269Y-254906D01*
X561813Y-111713D02*
X562120Y-111406D01*
X551707Y-120555D02*
X551813Y-120661D01*
D21*
X451181Y-324852D02*
G03*
X451613Y-323809I-1043J1043D01*
G01*
X439187Y-321492D02*
G03*
X439186Y-321493I3360J-3360D01*
G01*
X447244Y-324852D02*
G03*
X447676Y-323809I-1043J1043D01*
G01*
X441339Y-321309D02*
G03*
X440551Y-323210I1901J-1901D01*
G01*
X459487Y-322093D02*
G03*
X460630Y-324852I3902J0D01*
G01*
X439370Y-321309D02*
G03*
X439802Y-320266I-1043J1043D01*
G01*
X453582Y-323995D02*
G03*
X453937Y-324852I1212J0D01*
G01*
X457480D02*
G03*
X457519Y-324758I-94J94D01*
G01*
X441339Y-321309D02*
G03*
X441771Y-320265I-1044J1044D01*
G01*
X431938Y-322836D02*
G03*
X431102Y-324852I2016J-2016D01*
G01*
X439186Y-321493D02*
G03*
X437795Y-324852I3361J-3359D01*
G01*
X445288Y-322478D02*
G03*
X445708Y-321463I-1015J1015D01*
G01*
X445288Y-322478D02*
G03*
X444488Y-324408I1930J-1930D01*
G01*
X434252Y-322490D02*
G03*
X435865Y-318595I-3894J3894D01*
G01*
X434252Y-322490D02*
G03*
X433858Y-323440I950J-950D01*
G01*
X433071Y-321702D02*
G03*
X433897Y-319708I-1995J1995D01*
G01*
X441771Y-306387D02*
G03*
X442126Y-306742I355J0D01*
G01*
X439370D02*
G03*
X439802Y-306310I0J432D01*
G01*
X453582Y-306387D02*
G03*
X453937Y-306742I355J0D01*
G01*
X451181D02*
G03*
X451613Y-306310I0J432D01*
G01*
X229921Y-388679D02*
G03*
X229331Y-387253I-2016J0D01*
G01*
X246328Y-386993D02*
G03*
X246293Y-387066I432J-252D01*
G01*
X246144Y-387379D02*
G03*
X246227Y-387239I-384J320D01*
G01*
X246143Y-387382D02*
G03*
X245669Y-388680I1543J-1298D01*
G01*
X249606Y-387729D02*
G03*
X249410Y-387253I-672J0D01*
G01*
X233858Y-392616D02*
G03*
X233268Y-391191I-2016J0D01*
G01*
X232480Y-389290D02*
G03*
X233268Y-391191I2688J0D01*
G01*
X435865Y-306386D02*
G03*
X436221Y-306742I355J0D01*
G01*
X212795Y-387253D02*
G03*
X210236Y-393432I6178J-6178D01*
G01*
X215945Y-387253D02*
G03*
X214173Y-391531I4277J-4277D01*
G01*
X433465Y-306742D02*
G03*
X433897Y-306309I0J433D01*
G01*
X262006Y-387255D02*
G03*
X261417Y-388680I1428J-1424D01*
G01*
X447676Y-306386D02*
G03*
X448032Y-306742I355J0D01*
G01*
X265354Y-387729D02*
G03*
X265158Y-387253I-672J0D01*
G01*
X445276Y-306742D02*
G03*
X445708Y-306309I0J433D01*
G01*
X249641Y-403994D02*
G03*
X249685Y-404100I150J0D01*
G01*
X248741Y-401821D02*
G03*
X249685Y-404100I3223J0D01*
G01*
X232741Y-401213D02*
G03*
X233937Y-404100I4083J0D01*
G01*
X229041Y-401785D02*
G03*
X230000Y-404100I3274J0D01*
G01*
X213341Y-401901D02*
G03*
X214252Y-404100I3110J0D01*
G01*
X440551Y-324852D02*
Y-323210D01*
X459487Y-322093D02*
Y-316492D01*
X453582Y-323995D02*
Y-316492D01*
X447676Y-323809D02*
Y-316492D01*
X439186Y-321493D02*
X439187Y-321492D01*
X444488Y-324408D02*
X444488Y-324411D01*
X451613Y-323809D02*
Y-316492D01*
X444488Y-324852D02*
Y-324411D01*
X433858Y-324852D02*
Y-323440D01*
X457519Y-324758D02*
Y-316492D01*
X439187Y-321492D02*
X439370Y-321309D01*
X431938Y-322836D02*
X433071Y-321702D01*
X433897Y-319708D02*
Y-316492D01*
X435865Y-318595D02*
Y-316492D01*
X439802Y-306310D02*
Y-300548D01*
X441771Y-306387D02*
Y-300548D01*
X453582Y-306387D02*
Y-300548D01*
X451613Y-306310D02*
Y-300548D01*
X451644Y-300579D01*
X445708Y-321463D02*
Y-316492D01*
X441771Y-320265D02*
Y-316492D01*
X229921Y-401427D02*
Y-388679D01*
X246328Y-386993D02*
X246338Y-386976D01*
X246227Y-387239D02*
X246293Y-387066D01*
X246143Y-387382D02*
X246144Y-387379D01*
X245669Y-401427D02*
Y-388680D01*
X249606Y-401427D02*
Y-387729D01*
X246338Y-386976D02*
X246339Y-386975D01*
X233858Y-401427D02*
Y-392616D01*
X232480Y-389290D02*
Y-387253D01*
X439802Y-320266D02*
Y-316492D01*
X435865Y-306386D02*
Y-300548D01*
X210236Y-401427D02*
Y-393432D01*
X433897Y-306309D02*
Y-300548D01*
X214173Y-401427D02*
Y-391531D01*
X261417Y-401427D02*
Y-388680D01*
X447676Y-306386D02*
Y-300548D01*
X265354Y-401427D02*
Y-387729D01*
X445708Y-306309D02*
Y-300548D01*
X245748Y-404100D02*
X246041Y-403807D01*
X245541Y-403893D02*
X245748Y-404100D01*
X264641Y-403308D02*
X265433Y-404100D01*
X261496D02*
X262241Y-403355D01*
D26*
X335925Y-124803D02*
D03*
X347539D02*
D03*
X359941Y-136221D02*
D03*
X371555D02*
D03*
X653839Y-260236D02*
D03*
X642224D02*
D03*
X359154Y-124803D02*
D03*
X370768D02*
D03*
D27*
X293445Y-245593D02*
D03*
X309193D02*
D03*
X293445Y-243593D02*
D03*
X309193D02*
D03*
X293445Y-241593D02*
D03*
X309193D02*
D03*
X293445Y-239593D02*
D03*
X309193D02*
D03*
X293445Y-237593D02*
D03*
X309193D02*
D03*
X293445Y-235593D02*
D03*
X309193D02*
D03*
X293445Y-233593D02*
D03*
X309193D02*
D03*
X293445Y-231593D02*
D03*
X309193D02*
D03*
X293445Y-229593D02*
D03*
X309193D02*
D03*
Y-227593D02*
D03*
X293445D02*
D03*
Y-245593D02*
D03*
X309193D02*
D03*
X293445Y-243593D02*
D03*
X309193D02*
D03*
X293445Y-241593D02*
D03*
X309193D02*
D03*
X293445Y-239593D02*
D03*
X309193D02*
D03*
X293445Y-237593D02*
D03*
X309193D02*
D03*
X293445Y-235593D02*
D03*
X309193D02*
D03*
X293445Y-233593D02*
D03*
X309193D02*
D03*
X293445Y-231593D02*
D03*
X309193D02*
D03*
X293445Y-229593D02*
D03*
X309193D02*
D03*
Y-227593D02*
D03*
X293445D02*
D03*
D28*
X639764Y-236221D02*
D03*
Y-241732D02*
D03*
X554419Y-216650D02*
D03*
Y-222161D02*
D03*
X602919Y-243661D02*
D03*
Y-238150D02*
D03*
X586419Y-243661D02*
D03*
Y-238150D02*
D03*
X596919Y-243661D02*
D03*
Y-238150D02*
D03*
X591919Y-243661D02*
D03*
Y-238150D02*
D03*
X82677Y-123228D02*
D03*
Y-128740D02*
D03*
X75845Y-116496D02*
D03*
Y-110984D02*
D03*
X500000Y-137647D02*
D03*
Y-132135D02*
D03*
X67913Y-335433D02*
D03*
Y-329921D02*
D03*
X601723Y-136417D02*
D03*
Y-141929D02*
D03*
X581250Y-136417D02*
D03*
Y-141929D02*
D03*
X588337Y-136417D02*
D03*
Y-141929D02*
D03*
X595030Y-136417D02*
D03*
Y-141929D02*
D03*
X544813Y-120161D02*
D03*
Y-114650D02*
D03*
X114173Y-73868D02*
D03*
Y-79379D02*
D03*
X98425Y-92568D02*
D03*
Y-98080D02*
D03*
X348106Y-104238D02*
D03*
Y-98726D02*
D03*
X447835Y-128592D02*
D03*
Y-123080D02*
D03*
X244094Y-115206D02*
D03*
Y-120718D02*
D03*
X67913Y-169488D02*
D03*
Y-175000D02*
D03*
X68898Y-275787D02*
D03*
Y-281299D02*
D03*
X68898Y-221654D02*
D03*
Y-227165D02*
D03*
X528543Y-112057D02*
D03*
Y-117569D02*
D03*
D29*
X600984Y-173622D02*
D03*
X562795D02*
D03*
X579824Y-274905D02*
D03*
X618013D02*
D03*
D30*
X560919Y-243150D02*
D03*
X565919D02*
D03*
X570919D02*
D03*
X575919D02*
D03*
Y-223661D02*
D03*
X570919D02*
D03*
X565919D02*
D03*
X560919D02*
D03*
X551813Y-120661D02*
D03*
X556813D02*
D03*
X561813D02*
D03*
X566813D02*
D03*
Y-140150D02*
D03*
X561813D02*
D03*
X556813D02*
D03*
X551813D02*
D03*
D31*
X549702Y-231906D02*
D03*
X555135D02*
D03*
X570757Y-206890D02*
D03*
X576191D02*
D03*
X571097Y-117206D02*
D03*
X576530D02*
D03*
X654291Y-249606D02*
D03*
X648858D02*
D03*
X618298Y-118307D02*
D03*
X623731D02*
D03*
X540597Y-128405D02*
D03*
X546030D02*
D03*
X561211Y-105315D02*
D03*
X566644D02*
D03*
X110709Y-263632D02*
D03*
X116142D02*
D03*
D32*
X547376Y-240905D02*
D03*
X554462D02*
D03*
X545857Y-138406D02*
D03*
X538770D02*
D03*
X619439Y-132480D02*
D03*
X626526D02*
D03*
X619439Y-141142D02*
D03*
X626526D02*
D03*
D33*
X610919Y-243949D02*
D03*
Y-236862D02*
D03*
X621919Y-243949D02*
D03*
Y-236862D02*
D03*
X648425Y-234252D02*
D03*
Y-241339D02*
D03*
X357480Y-96850D02*
D03*
Y-103937D02*
D03*
D34*
X582135Y-227795D02*
D03*
Y-233228D02*
D03*
X582419Y-217189D02*
D03*
Y-222622D02*
D03*
X573770Y-136063D02*
D03*
Y-141496D02*
D03*
D35*
X570761Y-212906D02*
D03*
X576076D02*
D03*
X566471Y-111406D02*
D03*
X561156D02*
D03*
D36*
X568569Y-254906D02*
D03*
X562269D02*
D03*
D37*
X672835Y-214469D02*
D03*
Y-240650D02*
D03*
Y-289862D02*
D03*
Y-263681D02*
D03*
D38*
X386914Y-160521D02*
D03*
X474906D02*
D03*
Y-308553D02*
D03*
X386914D02*
D03*
D39*
X424024Y-168449D02*
D03*
X422056D02*
D03*
X447647D02*
D03*
X463394D02*
D03*
X451584D02*
D03*
X443710D02*
D03*
X455521D02*
D03*
X433868D02*
D03*
X437805D02*
D03*
X453552Y-152505D02*
D03*
X445679D02*
D03*
X451584D02*
D03*
X463394D02*
D03*
X461427Y-168449D02*
D03*
X457489D02*
D03*
X406309D02*
D03*
X427961D02*
D03*
X447647Y-152505D02*
D03*
X457489D02*
D03*
X453552Y-168449D02*
D03*
X445679D02*
D03*
X441742D02*
D03*
X425993D02*
D03*
X461427Y-152505D02*
D03*
X435836Y-168449D02*
D03*
X431898D02*
D03*
X455521Y-152505D02*
D03*
X416151Y-168449D02*
D03*
X418119D02*
D03*
X412214Y-152505D02*
D03*
X406309D02*
D03*
X441742D02*
D03*
X443710D02*
D03*
X404340Y-168449D02*
D03*
X396465Y-152505D02*
D03*
X394498Y-168449D02*
D03*
X418119Y-152505D02*
D03*
X404340D02*
D03*
X414183D02*
D03*
X416151D02*
D03*
X422056D02*
D03*
X433868D02*
D03*
X427961D02*
D03*
X398434D02*
D03*
X408277D02*
D03*
X402372D02*
D03*
X435836D02*
D03*
X396465Y-168449D02*
D03*
X394498Y-152505D02*
D03*
X424024D02*
D03*
X437805D02*
D03*
X398434Y-168449D02*
D03*
X392529D02*
D03*
X402372D02*
D03*
X392529Y-152505D02*
D03*
X408277Y-168449D02*
D03*
X431898Y-152505D02*
D03*
X425993D02*
D03*
X412214Y-168449D02*
D03*
X465364Y-152505D02*
D03*
Y-168449D02*
D03*
X400403D02*
D03*
X410246D02*
D03*
X420088D02*
D03*
X429931D02*
D03*
X439773D02*
D03*
X449615D02*
D03*
X459457D02*
D03*
X400403Y-152505D02*
D03*
X410246D02*
D03*
X420088D02*
D03*
X429931D02*
D03*
X439773D02*
D03*
X449615D02*
D03*
X459457D02*
D03*
X469301D02*
D03*
Y-168449D02*
D03*
X467332D02*
D03*
X414183D02*
D03*
X467332Y-152505D02*
D03*
X437795Y-300625D02*
D03*
X439763D02*
D03*
X414173D02*
D03*
X398425D02*
D03*
X410236D02*
D03*
X418110D02*
D03*
X406299D02*
D03*
X427952D02*
D03*
X424015D02*
D03*
X408267Y-316569D02*
D03*
X416141D02*
D03*
X410236D02*
D03*
X398425D02*
D03*
X400393Y-300625D02*
D03*
X404330D02*
D03*
X455511D02*
D03*
X433858D02*
D03*
X414173Y-316569D02*
D03*
X404330D02*
D03*
X408267Y-300625D02*
D03*
X416141D02*
D03*
X420078D02*
D03*
X435826D02*
D03*
X400393Y-316569D02*
D03*
X425984Y-300625D02*
D03*
X429921D02*
D03*
X406299Y-316569D02*
D03*
X445669Y-300625D02*
D03*
X443700D02*
D03*
X449606Y-316569D02*
D03*
X455511D02*
D03*
X420078D02*
D03*
X418110D02*
D03*
X457480Y-300625D02*
D03*
X465354Y-316569D02*
D03*
X467322Y-300625D02*
D03*
X443700Y-316569D02*
D03*
X457480D02*
D03*
X447637D02*
D03*
X445669D02*
D03*
X439763D02*
D03*
X427952D02*
D03*
X433858D02*
D03*
X463385D02*
D03*
X453543D02*
D03*
X459448D02*
D03*
X425984D02*
D03*
X465354Y-300625D02*
D03*
X467322Y-316569D02*
D03*
X437795D02*
D03*
X424015D02*
D03*
X463385Y-300625D02*
D03*
X469291D02*
D03*
X459448D02*
D03*
X469291Y-316569D02*
D03*
X453543Y-300625D02*
D03*
X429921Y-316569D02*
D03*
X435826D02*
D03*
X449606Y-300625D02*
D03*
X396456Y-316569D02*
D03*
Y-300625D02*
D03*
X461417D02*
D03*
X451574D02*
D03*
X441732D02*
D03*
X431889D02*
D03*
X422047D02*
D03*
X412204D02*
D03*
X402362D02*
D03*
X461417Y-316569D02*
D03*
X451574D02*
D03*
X441732D02*
D03*
X431889D02*
D03*
X422047D02*
D03*
X412204D02*
D03*
X402362D02*
D03*
X392519D02*
D03*
Y-300625D02*
D03*
X394488D02*
D03*
X447637D02*
D03*
X394488Y-316569D02*
D03*
D40*
X528351Y-190049D02*
D03*
Y-278041D02*
D03*
X340949D02*
D03*
Y-190049D02*
D03*
D41*
X520423Y-227160D02*
D03*
Y-225192D02*
D03*
Y-250782D02*
D03*
Y-266530D02*
D03*
Y-254719D02*
D03*
Y-246845D02*
D03*
Y-258656D02*
D03*
Y-237003D02*
D03*
Y-240940D02*
D03*
X536367Y-256688D02*
D03*
Y-248814D02*
D03*
Y-254719D02*
D03*
Y-266530D02*
D03*
X520423Y-264562D02*
D03*
Y-260625D02*
D03*
Y-209444D02*
D03*
Y-231097D02*
D03*
X536367Y-250782D02*
D03*
Y-260625D02*
D03*
X520423Y-256688D02*
D03*
Y-248814D02*
D03*
Y-244877D02*
D03*
Y-229129D02*
D03*
X536367Y-264562D02*
D03*
X520423Y-238971D02*
D03*
Y-235034D02*
D03*
X536367Y-258656D02*
D03*
X520423Y-219286D02*
D03*
Y-221255D02*
D03*
X536367Y-215349D02*
D03*
Y-209444D02*
D03*
Y-244877D02*
D03*
Y-246845D02*
D03*
X520423Y-207475D02*
D03*
X536367Y-199601D02*
D03*
X520423Y-197633D02*
D03*
X536367Y-221255D02*
D03*
Y-207475D02*
D03*
Y-217318D02*
D03*
Y-219286D02*
D03*
Y-225192D02*
D03*
Y-237003D02*
D03*
Y-231097D02*
D03*
Y-201570D02*
D03*
Y-211412D02*
D03*
Y-205507D02*
D03*
Y-238971D02*
D03*
X520423Y-199601D02*
D03*
X536367Y-197633D02*
D03*
Y-227160D02*
D03*
Y-240940D02*
D03*
X520423Y-201570D02*
D03*
Y-195664D02*
D03*
Y-205507D02*
D03*
X536367Y-195664D02*
D03*
X520423Y-211412D02*
D03*
X536367Y-235034D02*
D03*
Y-229129D02*
D03*
X520423Y-215349D02*
D03*
X536367Y-268499D02*
D03*
X520423D02*
D03*
Y-203538D02*
D03*
Y-213381D02*
D03*
Y-223223D02*
D03*
Y-233066D02*
D03*
Y-242908D02*
D03*
Y-252751D02*
D03*
Y-262593D02*
D03*
X536367Y-203538D02*
D03*
Y-213381D02*
D03*
Y-223223D02*
D03*
Y-233066D02*
D03*
Y-242908D02*
D03*
Y-252751D02*
D03*
Y-262593D02*
D03*
Y-272436D02*
D03*
X520423D02*
D03*
Y-270467D02*
D03*
Y-217318D02*
D03*
X536367Y-270467D02*
D03*
X348876Y-240930D02*
D03*
Y-242898D02*
D03*
Y-217308D02*
D03*
Y-201560D02*
D03*
Y-213371D02*
D03*
Y-221245D02*
D03*
Y-209434D02*
D03*
Y-231087D02*
D03*
Y-227150D02*
D03*
X332932Y-211402D02*
D03*
Y-219276D02*
D03*
Y-213371D02*
D03*
Y-201560D02*
D03*
X348876Y-203528D02*
D03*
Y-207465D02*
D03*
Y-258646D02*
D03*
Y-236993D02*
D03*
X332932Y-217308D02*
D03*
Y-207465D02*
D03*
X348876Y-211402D02*
D03*
Y-219276D02*
D03*
Y-223213D02*
D03*
Y-238961D02*
D03*
X332932Y-203528D02*
D03*
X348876Y-229119D02*
D03*
Y-233056D02*
D03*
X332932Y-209434D02*
D03*
X348876Y-248804D02*
D03*
Y-246835D02*
D03*
X332932Y-252741D02*
D03*
Y-258646D02*
D03*
Y-223213D02*
D03*
Y-221245D02*
D03*
X348876Y-260615D02*
D03*
X332932Y-268489D02*
D03*
X348876Y-270457D02*
D03*
X332932Y-246835D02*
D03*
Y-260615D02*
D03*
Y-250772D02*
D03*
Y-248804D02*
D03*
Y-242898D02*
D03*
Y-231087D02*
D03*
Y-236993D02*
D03*
Y-266520D02*
D03*
Y-256678D02*
D03*
Y-262583D02*
D03*
Y-229119D02*
D03*
X348876Y-268489D02*
D03*
X332932Y-270457D02*
D03*
Y-240930D02*
D03*
Y-227150D02*
D03*
X348876Y-266520D02*
D03*
Y-272426D02*
D03*
Y-262583D02*
D03*
X332932Y-272426D02*
D03*
X348876Y-256678D02*
D03*
X332932Y-233056D02*
D03*
Y-238961D02*
D03*
X348876Y-252741D02*
D03*
X332932Y-199591D02*
D03*
X348876D02*
D03*
Y-264552D02*
D03*
Y-254709D02*
D03*
Y-244867D02*
D03*
Y-235024D02*
D03*
Y-225182D02*
D03*
Y-215339D02*
D03*
Y-205497D02*
D03*
X332932Y-264552D02*
D03*
Y-254709D02*
D03*
Y-244867D02*
D03*
Y-235024D02*
D03*
Y-225182D02*
D03*
Y-215339D02*
D03*
Y-205497D02*
D03*
Y-195654D02*
D03*
X348876D02*
D03*
Y-197623D02*
D03*
Y-250772D02*
D03*
X332932Y-197623D02*
D03*
D42*
X630240Y-37647D02*
D03*
X649390D02*
D03*
Y-29773D02*
D03*
X630240D02*
D03*
Y-21899D02*
D03*
X649390D02*
D03*
X630240Y-14025D02*
D03*
X649390D02*
D03*
X74036Y-73671D02*
D03*
X93186D02*
D03*
X74036Y-65797D02*
D03*
X93186D02*
D03*
Y-57923D02*
D03*
X74036D02*
D03*
Y-50049D02*
D03*
X93186D02*
D03*
D43*
X609291Y-316535D02*
D03*
Y-343543D02*
D03*
X599291Y-316535D02*
D03*
Y-343543D02*
D03*
X589291Y-316535D02*
D03*
Y-343543D02*
D03*
X579291Y-316535D02*
D03*
Y-343543D02*
D03*
X569291Y-316535D02*
D03*
Y-343543D02*
D03*
D44*
X262806Y-132277D02*
D03*
X257294D02*
D03*
X248031Y-127165D02*
D03*
X242520D02*
D03*
X59646Y-316929D02*
D03*
X54134D02*
D03*
X60827Y-210630D02*
D03*
X55315D02*
D03*
X60827Y-262795D02*
D03*
X55315D02*
D03*
X54331Y-157480D02*
D03*
X59842D02*
D03*
D45*
X540493Y-331738D02*
D03*
X532619D02*
D03*
X540099Y-347880D02*
D03*
X532225D02*
D03*
D46*
X655118Y-346457D02*
D03*
Y-338583D02*
D03*
X637008Y-346850D02*
D03*
Y-338976D02*
D03*
D47*
X515198Y-329179D02*
D03*
Y-334297D02*
D03*
X524056Y-331738D02*
D03*
X515099Y-345321D02*
D03*
Y-350439D02*
D03*
X523958Y-347880D02*
D03*
D48*
X639567Y-320374D02*
D03*
X634449D02*
D03*
X637008Y-329232D02*
D03*
X658268Y-320473D02*
D03*
X653150D02*
D03*
X655709Y-329331D02*
D03*
D49*
X81988Y-215551D02*
D03*
Y-213583D02*
D03*
Y-211614D02*
D03*
Y-209646D02*
D03*
X69587D02*
D03*
Y-211614D02*
D03*
Y-213583D02*
D03*
Y-215551D02*
D03*
X81004Y-162402D02*
D03*
Y-160433D02*
D03*
Y-158465D02*
D03*
Y-156496D02*
D03*
X68602D02*
D03*
Y-158465D02*
D03*
Y-160433D02*
D03*
Y-162402D02*
D03*
X81988Y-267717D02*
D03*
Y-265748D02*
D03*
Y-263779D02*
D03*
Y-261811D02*
D03*
X69587D02*
D03*
Y-263779D02*
D03*
Y-265748D02*
D03*
Y-267717D02*
D03*
X81004Y-321850D02*
D03*
Y-319882D02*
D03*
Y-317913D02*
D03*
Y-315945D02*
D03*
X68602D02*
D03*
Y-317913D02*
D03*
Y-319882D02*
D03*
Y-321850D02*
D03*
D50*
X649390Y-14025D02*
D03*
Y-29773D02*
D03*
Y-21899D02*
D03*
Y-37647D02*
D03*
X631890Y-14025D02*
D03*
Y-21899D02*
D03*
Y-29773D02*
D03*
Y-37647D02*
D03*
X74036Y-73671D02*
D03*
Y-57923D02*
D03*
Y-65797D02*
D03*
Y-50049D02*
D03*
X91536Y-73671D02*
D03*
Y-65797D02*
D03*
Y-57923D02*
D03*
Y-50049D02*
D03*
D51*
X40354Y14764D02*
D03*
Y8858D02*
D03*
X33465Y14764D02*
D03*
Y8858D02*
D03*
X26575Y14764D02*
D03*
Y8858D02*
D03*
X47244Y14764D02*
D03*
Y8858D02*
D03*
D52*
Y-4626D02*
D03*
Y689D02*
D03*
X40354Y-4626D02*
D03*
Y689D02*
D03*
X33465Y-4626D02*
D03*
Y689D02*
D03*
X26575Y-4626D02*
D03*
Y689D02*
D03*
X199803Y-119439D02*
D03*
Y-114517D02*
D03*
D53*
X94193Y-120079D02*
D03*
Y-122047D02*
D03*
Y-124016D02*
D03*
Y-125984D02*
D03*
Y-127953D02*
D03*
Y-129921D02*
D03*
Y-131890D02*
D03*
X112500D02*
D03*
Y-129921D02*
D03*
Y-127953D02*
D03*
Y-125984D02*
D03*
Y-124016D02*
D03*
Y-122047D02*
D03*
Y-120079D02*
D03*
D54*
X97441Y-135138D02*
D03*
X99410D02*
D03*
X101378D02*
D03*
X103347D02*
D03*
X105315D02*
D03*
X107283D02*
D03*
X109252D02*
D03*
X109252Y-116831D02*
D03*
X107283D02*
D03*
X105315D02*
D03*
X103347D02*
D03*
X101378D02*
D03*
X99410D02*
D03*
X97441D02*
D03*
D55*
X103347Y-125984D02*
D03*
D56*
X-18406Y-187795D02*
D03*
Y-176772D02*
D03*
Y-240551D02*
D03*
Y-229528D02*
D03*
Y-294094D02*
D03*
Y-283071D02*
D03*
Y-346850D02*
D03*
Y-335827D02*
D03*
Y-113976D02*
D03*
Y-102953D02*
D03*
Y-70669D02*
D03*
Y-59646D02*
D03*
D57*
X-19685Y-184055D02*
D03*
Y-180512D02*
D03*
Y-236811D02*
D03*
Y-233268D02*
D03*
Y-290354D02*
D03*
Y-286811D02*
D03*
Y-343110D02*
D03*
Y-339567D02*
D03*
Y-110236D02*
D03*
Y-106693D02*
D03*
Y-66929D02*
D03*
Y-63386D02*
D03*
D58*
X82677Y-116535D02*
D03*
Y-109843D02*
D03*
D59*
X82677Y-135827D02*
D03*
X76772D02*
D03*
D60*
X75787Y-127756D02*
D03*
Y-123031D02*
D03*
D61*
X44291Y-256988D02*
D03*
Y-268602D02*
D03*
Y-151673D02*
D03*
Y-163287D02*
D03*
Y-311122D02*
D03*
Y-322736D02*
D03*
Y-204823D02*
D03*
Y-216437D02*
D03*
D62*
X38287Y-262795D02*
D03*
Y-157480D02*
D03*
Y-316929D02*
D03*
Y-210630D02*
D03*
D63*
X74803Y-335630D02*
D03*
Y-329724D02*
D03*
X82677Y-335630D02*
D03*
Y-329724D02*
D03*
X75787Y-227362D02*
D03*
Y-221457D02*
D03*
X82677Y-227362D02*
D03*
Y-221457D02*
D03*
X83661Y-281496D02*
D03*
Y-275590D02*
D03*
X75787Y-281496D02*
D03*
Y-275590D02*
D03*
X74803Y-175197D02*
D03*
Y-169291D02*
D03*
X82677Y-175197D02*
D03*
Y-169291D02*
D03*
X399606Y-134695D02*
D03*
Y-128789D02*
D03*
X405512Y-134695D02*
D03*
Y-128789D02*
D03*
D64*
X487205Y-137647D02*
D03*
X481693D02*
D03*
X650197Y-50049D02*
D03*
X644685D02*
D03*
X615522Y-14017D02*
D03*
X610010D02*
D03*
X263976Y-112057D02*
D03*
X269488D02*
D03*
X518701D02*
D03*
X513189D02*
D03*
D65*
X460925Y-137647D02*
D03*
X456398D02*
D03*
D66*
X643701Y-58907D02*
D03*
X651575D02*
D03*
X609252Y-21506D02*
D03*
X617126D02*
D03*
D67*
X89567Y-98277D02*
D03*
Y-90403D02*
D03*
X123031Y-79970D02*
D03*
Y-72096D02*
D03*
D68*
X31496Y-184055D02*
D03*
Y-291732D02*
D03*
D69*
X38189Y-184055D02*
D03*
Y-175394D02*
D03*
X30709D02*
D03*
X38189Y-291732D02*
D03*
Y-283071D02*
D03*
X30709D02*
D03*
D70*
X267323Y-126821D02*
D03*
X262205D02*
D03*
X267323Y-118947D02*
D03*
X262205D02*
D03*
D71*
X276969Y-357824D02*
D03*
Y-354478D02*
D03*
X221850Y-357824D02*
D03*
Y-354478D02*
D03*
D72*
X281102Y-401427D02*
D03*
X159055D02*
D03*
X155118D02*
D03*
X151181D02*
D03*
X178740D02*
D03*
X222047D02*
D03*
X265354D02*
D03*
X261417D02*
D03*
X249606D02*
D03*
X245669D02*
D03*
X233858D02*
D03*
X229921D02*
D03*
X214173D02*
D03*
X210236D02*
D03*
X186614D02*
D03*
X182677D02*
D03*
X202362D02*
D03*
X273228D02*
D03*
X166929D02*
D03*
X170866D02*
D03*
X190551D02*
D03*
X269291D02*
D03*
X257480D02*
D03*
X241732D02*
D03*
X237795D02*
D03*
X174803D02*
D03*
X162992D02*
D03*
X253543D02*
D03*
X206299D02*
D03*
X218110D02*
D03*
X225984D02*
D03*
D73*
X277165Y-399477D02*
D03*
D74*
X279528Y-113946D02*
D03*
Y-118947D02*
D03*
Y-123946D02*
D03*
Y-128946D02*
D03*
X298425Y-113946D02*
D03*
Y-118947D02*
D03*
Y-123946D02*
D03*
Y-128946D02*
D03*
D75*
X209252Y-114399D02*
D03*
Y-119399D02*
D03*
Y-124399D02*
D03*
Y-129399D02*
D03*
X227756Y-114399D02*
D03*
Y-119399D02*
D03*
Y-124399D02*
D03*
Y-129399D02*
D03*
D76*
X481250Y-121899D02*
D03*
Y-123868D02*
D03*
Y-125836D02*
D03*
Y-127805D02*
D03*
X491191D02*
D03*
Y-125836D02*
D03*
Y-123868D02*
D03*
Y-121899D02*
D03*
D77*
X484252Y-128838D02*
D03*
X486221D02*
D03*
X488189D02*
D03*
Y-120866D02*
D03*
X486221D02*
D03*
X484252D02*
D03*
D78*
X519783Y-126131D02*
D03*
Y-128691D02*
D03*
X511713D02*
D03*
Y-126131D02*
D03*
Y-123572D02*
D03*
Y-121013D02*
D03*
X519783D02*
D03*
Y-123572D02*
D03*
D79*
X464370Y-130034D02*
D03*
X456890D02*
D03*
Y-121639D02*
D03*
X460630D02*
D03*
D80*
X464370D02*
D03*
D81*
X548425Y-157087D02*
D03*
Y-150787D02*
D03*
D82*
X618012Y-124409D02*
D03*
X623721D02*
D03*
D83*
X237205Y-125639D02*
D03*
Y-120127D02*
D03*
D149*
X387598Y-124606D02*
G03*
X391781Y-128789I4183J0D01*
G01*
X586419Y-224600D02*
G03*
X585836Y-223189I-2000J0D01*
G01*
X268922Y-392732D02*
G03*
X268428Y-391417I-2000J-0D01*
G01*
X218189Y-393476D02*
G03*
X217391Y-391877I-2000J-0D01*
G01*
X391781Y-128789D02*
X399606D01*
X406683Y-123769D02*
X412303D01*
X586419Y-238150D02*
Y-224600D01*
X585679Y-223031D02*
X585836Y-223189D01*
X585836Y-223189D01*
X588976Y-302756D02*
X589291Y-303071D01*
Y-316535D02*
Y-303071D01*
X579291Y-303386D02*
X579528Y-303150D01*
X579291Y-316535D02*
Y-303386D01*
X106299Y-263632D02*
Y-254331D01*
X90041Y-238072D02*
X106299Y-254331D01*
X78772Y-238072D02*
X90041D01*
X545835Y-138406D02*
Y-134234D01*
X563872Y-235674D02*
X565919Y-237720D01*
X623731Y-124409D02*
Y-118307D01*
X623721Y-124409D02*
X623731D01*
X568569Y-263650D02*
X579824Y-274905D01*
X568569Y-263650D02*
Y-254906D01*
X570919Y-252555D01*
Y-243150D01*
X548425Y-163386D02*
Y-157087D01*
Y-163386D02*
X558661Y-173622D01*
X562795D01*
X548425Y-157087D02*
X552756D01*
X561813Y-148029D01*
Y-140150D01*
X159134Y-404100D02*
Y-391118D01*
X155197Y-389669D02*
X156441Y-388425D01*
X155035Y-389506D02*
X156116Y-388425D01*
X152964Y-389506D02*
X155035D01*
X155197Y-404100D02*
Y-389669D01*
X151260Y-404100D02*
Y-391210D01*
X156116Y-388425D02*
X156441D01*
X151260Y-391210D02*
X152964Y-389506D01*
X163006Y-404035D02*
Y-390730D01*
Y-404035D02*
X163071Y-404100D01*
X626526Y-132480D02*
X632432D01*
X268922Y-401057D02*
Y-392732D01*
Y-392732D01*
X268922D02*
X268922D01*
X281201Y-404080D02*
Y-390009D01*
X251378D02*
X253223Y-391854D01*
X241811Y-404100D02*
Y-397250D01*
X218189Y-393476D02*
Y-393476D01*
X226002Y-404039D02*
Y-390783D01*
X218189Y-393476D02*
X218189D01*
Y-404100D02*
Y-393476D01*
X206213Y-403935D02*
Y-391498D01*
X174882Y-404100D02*
Y-390659D01*
X251456Y-390009D02*
X255217D01*
X251378D02*
X251456D01*
X626526Y-141142D02*
X632432D01*
X267204Y-390009D02*
X268428Y-391417D01*
X216162Y-390947D02*
X217391Y-391877D01*
X281181Y-404100D02*
X281201Y-404080D01*
X235144Y-390416D02*
X240536D01*
X235230Y-390502D02*
X236624D01*
X235144Y-390416D02*
X235230Y-390502D01*
X241707Y-397146D02*
X241811Y-397250D01*
X240536Y-390416D02*
X241707Y-391587D01*
X268922Y-401057D02*
X269291Y-401427D01*
X226002Y-390783D02*
X226063Y-390722D01*
X257111Y-401057D02*
Y-391904D01*
X206213Y-403935D02*
X206378Y-404100D01*
X255217Y-390009D02*
X257111Y-391904D01*
X253223Y-401107D02*
X253543Y-401427D01*
X253223Y-401107D02*
Y-391854D01*
X205315Y-390600D02*
X206213Y-391498D01*
X236624Y-390502D02*
X237795Y-391673D01*
X241707Y-401402D02*
X241732Y-401427D01*
X241707Y-401402D02*
Y-397146D01*
X237795Y-401427D02*
Y-391673D01*
X174882Y-390659D02*
X174941Y-390600D01*
X202441D02*
X205315D01*
X257111Y-401057D02*
X257480Y-401427D01*
X241707Y-397146D02*
Y-391587D01*
X555364Y-249410D02*
Y-241807D01*
X553791Y-240235D02*
X555364Y-241807D01*
X565919Y-243150D02*
Y-237720D01*
X552620Y-235674D02*
X563872D01*
X553791Y-240235D02*
Y-236846D01*
X552620Y-235674D02*
X553791Y-236846D01*
X550487Y-235674D02*
X552620D01*
X549702Y-234890D02*
X550487Y-235674D01*
X549702Y-234890D02*
Y-231906D01*
X630954Y-270472D02*
Y-240158D01*
X627659Y-236862D02*
X630954Y-240158D01*
X621919Y-236862D02*
X627659D01*
X610919D02*
X621919D01*
X610183Y-237598D02*
X610919Y-236862D01*
X603470Y-237598D02*
X610183D01*
X602919Y-238150D02*
X603470Y-237598D01*
X586419Y-238150D02*
X591919D01*
X596919D02*
X602919D01*
X591919D02*
X596919D01*
X585679Y-223031D02*
X599065D01*
X585269Y-222622D02*
X585679Y-223031D01*
X582419Y-222622D02*
X585269D01*
X626521Y-274905D02*
X630954Y-270472D01*
X618013Y-274905D02*
X626521D01*
X89567Y-90797D02*
X89961Y-90403D01*
X88976Y-90797D02*
X89567D01*
X412303Y-123769D02*
X412339Y-123805D01*
X114075Y-73769D02*
X114458Y-73386D01*
X118166D02*
X118908Y-72644D01*
X122877D02*
X123031Y-72490D01*
X118908Y-72644D02*
X122877D01*
X114458Y-73386D02*
X118166D01*
X123031Y-72490D02*
X131693D01*
X600148Y-136417D02*
X601215Y-135350D01*
X405512Y-124941D02*
X406683Y-123769D01*
X405512Y-128789D02*
Y-124941D01*
X399606Y-128789D02*
X405512D01*
X269653Y-112222D02*
X274555D01*
X276280Y-113946D02*
X279528D01*
X269488Y-112057D02*
Y-106348D01*
X269685Y-106151D01*
X274555Y-112222D02*
X276280Y-113946D01*
X269488Y-112057D02*
X269653Y-112222D01*
X237579Y-114399D02*
X238189Y-115009D01*
X243898D02*
X244094Y-115206D01*
X238189Y-115009D02*
X243898D01*
X227756Y-114399D02*
X237579D01*
X78740Y-238041D02*
X78772Y-238072D01*
X131693Y-72490D02*
X131890Y-72687D01*
X178740Y-401427D02*
Y-389222D01*
X534400Y-126969D02*
X535837Y-128405D01*
X540597D01*
X541014Y-131417D02*
Y-128823D01*
X542668Y-133071D02*
X546998D01*
X540597Y-128405D02*
X541014Y-128823D01*
Y-131417D02*
X542668Y-133071D01*
X98425Y-92568D02*
X98819Y-92175D01*
X104528D01*
X106299Y-263632D02*
X110709D01*
X89961Y-90403D02*
X94488D01*
X95587Y-91502D01*
X97358D02*
X98425Y-92568D01*
X95587Y-91502D02*
X97358D01*
X83661Y-85482D02*
Y-75639D01*
Y-85482D02*
X88976Y-90797D01*
X74036Y-73671D02*
X81693D01*
X83661Y-75639D01*
X91634Y-73769D02*
X114075D01*
X91536Y-73671D02*
X91634Y-73769D01*
X179921Y-388041D02*
X182677D01*
X576132Y-124606D02*
X581250Y-129724D01*
X576530Y-123884D02*
Y-117206D01*
X576132Y-124606D02*
Y-124282D01*
X581250Y-136417D02*
Y-129724D01*
X576132Y-124282D02*
X576530Y-123884D01*
X581053Y-136221D02*
X581250Y-136417D01*
X581349D02*
X588337D01*
X595030D01*
X600148D01*
X178819Y-404100D02*
X179126Y-403793D01*
X178740Y-389222D02*
X179921Y-388041D01*
X545835Y-134234D02*
X546998Y-133071D01*
X554872D01*
X556813Y-135012D01*
Y-140150D02*
Y-135012D01*
X599917Y-172555D02*
X600984Y-173622D01*
D150*
X387598Y-124606D02*
X397638Y-114567D01*
X380315Y-131890D02*
X387598Y-124606D01*
X397638Y-114567D02*
X432283D01*
X452756Y-94095D01*
X574803D01*
X592913Y-112205D01*
Y-126378D02*
Y-112205D01*
X380315Y-138189D02*
Y-131890D01*
D151*
X562598Y-306693D02*
X569291D01*
Y-316535D02*
Y-306693D01*
X609291Y-305512D02*
X615748D01*
X609291Y-316535D02*
Y-305512D01*
X348106Y-98726D02*
Y-89891D01*
X348211D01*
X357480Y-96850D02*
Y-89963D01*
X357798D01*
D152*
X651750Y-58732D02*
Y-54161D01*
X651014Y-53425D02*
X651750Y-54161D01*
X651557Y-58925D02*
X651750Y-58732D01*
X651014Y-53425D02*
Y-50866D01*
X650197Y-50049D02*
X651014Y-50866D01*
X651557Y-64306D02*
Y-58925D01*
X650197Y-50049D02*
X661417D01*
X668307Y-43159D01*
Y-19537D01*
X662795Y-14025D02*
X668307Y-19537D01*
X649390Y-14025D02*
X662795D01*
D153*
X244094Y-115206D02*
Y-109104D01*
D154*
X155526Y-370989D02*
D03*
D155*
X155364Y-388287D02*
D03*
D156*
X182687Y-388238D02*
D03*
D157*
X142362Y-120079D02*
D03*
X152362D02*
D03*
X162362D02*
D03*
X579055Y13937D02*
D03*
X569055D02*
D03*
X559055D02*
D03*
X549055D02*
D03*
X539055D02*
D03*
X589055Y3937D02*
D03*
X579055D02*
D03*
X569055D02*
D03*
X559055D02*
D03*
X549055D02*
D03*
X539055D02*
D03*
D158*
X172362Y-120079D02*
D03*
X589055Y13937D02*
D03*
D159*
X258472Y-327165D02*
D03*
X282283D02*
D03*
X294094D02*
D03*
X302362Y-156693D02*
D03*
Y-316535D02*
D03*
X142520D02*
D03*
Y-236614D02*
D03*
Y-156693D02*
D03*
X270472Y-327165D02*
D03*
X246472D02*
D03*
D160*
X674409Y-194488D02*
D03*
Y-161417D02*
D03*
X348211Y-89891D02*
D03*
X357798Y-89963D02*
D03*
D161*
X645669Y-194488D02*
D03*
X624016D02*
D03*
Y-177953D02*
D03*
X645669D02*
D03*
X624016Y-161417D02*
D03*
X645669D02*
D03*
D162*
X391545Y-160477D02*
D03*
X470285D02*
D03*
X528395Y-194680D02*
D03*
Y-273420D02*
D03*
X470275Y-308597D02*
D03*
X391535D02*
D03*
X340904Y-273410D02*
D03*
Y-194670D02*
D03*
D163*
X604291Y-330039D02*
D03*
X574291D02*
D03*
D164*
X-18464Y-326781D02*
D03*
X1535D02*
D03*
Y-306781D02*
D03*
X-18464D02*
D03*
X-18465Y-273630D02*
D03*
X1535D02*
D03*
Y-253630D02*
D03*
X-18465D02*
D03*
Y-220480D02*
D03*
X1535D02*
D03*
Y-200480D02*
D03*
X-18465D02*
D03*
X-18464Y-167332D02*
D03*
X1535D02*
D03*
Y-147332D02*
D03*
X-18464D02*
D03*
D165*
X-8465Y-316781D02*
D03*
X-8465Y-263630D02*
D03*
Y-210480D02*
D03*
X-8465Y-157332D02*
D03*
D166*
X0Y0D02*
D03*
X0Y-378395D02*
D03*
X685039Y0D02*
D03*
X685039Y-340551D02*
D03*
X486221Y-340551D02*
D03*
D167*
X416835Y-196581D02*
D03*
X411811Y-196850D02*
D03*
X593307Y-127953D02*
D03*
X570866Y-70472D02*
D03*
Y-72441D02*
D03*
Y-74410D02*
D03*
X574016Y-70472D02*
D03*
Y-72441D02*
D03*
Y-74410D02*
D03*
X350787Y-116929D02*
D03*
X352756D02*
D03*
X354724D02*
D03*
X350787Y-113779D02*
D03*
X352756D02*
D03*
X354724D02*
D03*
X379134Y-137795D02*
D03*
X375984Y-120079D02*
D03*
X375532Y-123610D02*
D03*
X314658Y-244775D02*
D03*
X315097Y-235081D02*
D03*
X315226Y-230634D02*
D03*
X314864Y-227997D02*
D03*
X314503Y-225180D02*
D03*
X288583Y-225590D02*
D03*
X288189Y-228740D02*
D03*
Y-231102D02*
D03*
X288057Y-233478D02*
D03*
X288057Y-245095D02*
D03*
X288189Y-247638D02*
D03*
X287941Y-241819D02*
D03*
X288189Y-235827D02*
D03*
X588976Y-302756D02*
D03*
X579528Y-303150D02*
D03*
X615748Y-305512D02*
D03*
X562598Y-306693D02*
D03*
X330709Y-120473D02*
D03*
Y-123425D02*
D03*
X121063Y-263632D02*
D03*
X375590Y-127165D02*
D03*
X106299Y-263632D02*
D03*
X330709Y-126378D02*
D03*
X600000Y-146063D02*
D03*
X598032D02*
D03*
X596063D02*
D03*
X587008D02*
D03*
X585039D02*
D03*
X583071D02*
D03*
X575984Y-145669D02*
D03*
X574016D02*
D03*
X572047D02*
D03*
X593307Y-131102D02*
D03*
X595276D02*
D03*
X597244D02*
D03*
X595276Y-127953D02*
D03*
X597244D02*
D03*
X650787Y-229921D02*
D03*
X645669Y-230315D02*
D03*
X641732D02*
D03*
X638189D02*
D03*
X640945Y-250394D02*
D03*
Y-248425D02*
D03*
Y-246457D02*
D03*
X637795Y-250394D02*
D03*
Y-248425D02*
D03*
Y-246457D02*
D03*
X654724Y-211417D02*
D03*
X656693D02*
D03*
X658661D02*
D03*
X654724Y-208268D02*
D03*
X656693D02*
D03*
X658661D02*
D03*
X675591Y-298819D02*
D03*
X673622D02*
D03*
X671654D02*
D03*
X675591Y-301969D02*
D03*
X673622D02*
D03*
X671654D02*
D03*
X157480Y-358661D02*
D03*
X155512D02*
D03*
X153543D02*
D03*
X157480Y-361811D02*
D03*
X155512D02*
D03*
X153543D02*
D03*
X154724Y-389616D02*
D03*
X156693D02*
D03*
X158661D02*
D03*
X154724Y-386466D02*
D03*
X156693D02*
D03*
X158661D02*
D03*
X575919Y-236906D02*
D03*
X596702Y-247441D02*
D03*
X591978D02*
D03*
X586466D02*
D03*
X580954Y-207189D02*
D03*
X580935Y-237412D02*
D03*
X554519Y-212889D02*
D03*
X546419Y-246106D02*
D03*
X626819Y-244005D02*
D03*
X611094Y-248110D02*
D03*
X603002Y-247441D02*
D03*
X531496Y-262647D02*
D03*
X461811Y-310679D02*
D03*
X450000Y-293750D02*
D03*
X422441Y-293789D02*
D03*
X531496Y-213435D02*
D03*
X338525Y-243567D02*
D03*
X525591Y-233088D02*
D03*
X439697Y-162549D02*
D03*
X343144Y-225173D02*
D03*
X420669Y-157923D02*
D03*
X531496Y-223277D02*
D03*
X338583Y-235236D02*
D03*
X525591Y-242962D02*
D03*
X430150Y-162253D02*
D03*
X343444Y-215373D02*
D03*
X432283Y-293750D02*
D03*
X410528Y-157923D02*
D03*
X342944Y-264473D02*
D03*
X444095Y-293750D02*
D03*
X422835Y-311072D02*
D03*
X531496Y-233088D02*
D03*
X430150Y-157923D02*
D03*
X338444Y-225173D02*
D03*
X402756Y-311072D02*
D03*
X525591Y-253969D02*
D03*
X420079Y-162549D02*
D03*
X343403Y-205651D02*
D03*
X525591Y-203592D02*
D03*
X400295Y-157824D02*
D03*
X343144Y-254773D02*
D03*
X431928Y-311189D02*
D03*
X531496Y-242962D02*
D03*
X338844Y-215273D02*
D03*
X402362Y-293750D02*
D03*
X525591Y-262647D02*
D03*
X410913Y-162758D02*
D03*
X338444Y-264473D02*
D03*
X456299Y-293750D02*
D03*
X437795Y-293750D02*
D03*
X525591Y-213435D02*
D03*
X459319Y-162510D02*
D03*
Y-157922D02*
D03*
X342744Y-243747D02*
D03*
X412598Y-311072D02*
D03*
X531496Y-253969D02*
D03*
X449803Y-157923D02*
D03*
X338744Y-205473D02*
D03*
X531496Y-203592D02*
D03*
X401279Y-162509D02*
D03*
X439961Y-157923D02*
D03*
X338444Y-254773D02*
D03*
X461417Y-293750D02*
D03*
X525591Y-223277D02*
D03*
X449508Y-162549D02*
D03*
X343504Y-235236D02*
D03*
X412205Y-293750D02*
D03*
X639750Y-314581D02*
D03*
X658647Y-314581D02*
D03*
X509405Y-345138D02*
D03*
X509011Y-330177D02*
D03*
X56441Y-143600D02*
D03*
Y-151600D02*
D03*
Y-191600D02*
D03*
Y-199600D02*
D03*
Y-215600D02*
D03*
Y-223600D02*
D03*
Y-231600D02*
D03*
Y-247600D02*
D03*
Y-255600D02*
D03*
Y-271600D02*
D03*
Y-279600D02*
D03*
Y-287600D02*
D03*
Y-303600D02*
D03*
Y-311600D02*
D03*
Y-327600D02*
D03*
Y-335600D02*
D03*
Y-343600D02*
D03*
Y-351600D02*
D03*
X54441Y-139600D02*
D03*
X52441Y-143600D02*
D03*
X54441Y-147600D02*
D03*
X52441Y-151600D02*
D03*
Y-191600D02*
D03*
X54441Y-195600D02*
D03*
X52441Y-199600D02*
D03*
X54441Y-203600D02*
D03*
X52441Y-215600D02*
D03*
X54441Y-219600D02*
D03*
X52441Y-223600D02*
D03*
X54441Y-227600D02*
D03*
X52441Y-231600D02*
D03*
X54441Y-235600D02*
D03*
Y-243600D02*
D03*
X52441Y-247600D02*
D03*
X54441Y-251600D02*
D03*
X52441Y-255600D02*
D03*
X54441Y-267600D02*
D03*
X52441Y-271600D02*
D03*
X54441Y-275600D02*
D03*
X52441Y-279600D02*
D03*
Y-287600D02*
D03*
X54441Y-291600D02*
D03*
Y-299600D02*
D03*
X52441Y-303600D02*
D03*
X54441Y-307600D02*
D03*
X52441Y-311600D02*
D03*
X54441Y-323600D02*
D03*
X52441Y-327600D02*
D03*
X54441Y-331600D02*
D03*
X52441Y-335600D02*
D03*
X54441Y-339600D02*
D03*
X52441Y-343600D02*
D03*
Y-351600D02*
D03*
X50441Y-139600D02*
D03*
X48441Y-143600D02*
D03*
X50441Y-195600D02*
D03*
X48441Y-199600D02*
D03*
Y-223600D02*
D03*
X50441Y-227600D02*
D03*
X48441Y-231600D02*
D03*
X50441Y-235600D02*
D03*
Y-243600D02*
D03*
X48441Y-247600D02*
D03*
X50441Y-251600D02*
D03*
Y-275600D02*
D03*
X48441Y-279600D02*
D03*
Y-287600D02*
D03*
X50441Y-291600D02*
D03*
Y-299600D02*
D03*
X48441Y-303600D02*
D03*
X50441Y-331600D02*
D03*
X48441Y-335600D02*
D03*
X50441Y-339600D02*
D03*
X48441Y-343600D02*
D03*
Y-351600D02*
D03*
X46441Y-139600D02*
D03*
X44441Y-143600D02*
D03*
X46441Y-227600D02*
D03*
X44441Y-231600D02*
D03*
X46441Y-235600D02*
D03*
Y-243600D02*
D03*
X44441Y-247600D02*
D03*
Y-279600D02*
D03*
Y-287600D02*
D03*
X46441Y-291600D02*
D03*
Y-299600D02*
D03*
Y-331600D02*
D03*
X44441Y-335600D02*
D03*
X46441Y-339600D02*
D03*
X44441Y-343600D02*
D03*
Y-351600D02*
D03*
X42441Y-139600D02*
D03*
X40441Y-143600D02*
D03*
Y-223600D02*
D03*
X42441Y-227600D02*
D03*
X40441Y-231600D02*
D03*
X42441Y-235600D02*
D03*
Y-243600D02*
D03*
X40441Y-247600D02*
D03*
X42441Y-299600D02*
D03*
Y-331600D02*
D03*
X40441Y-335600D02*
D03*
X42441Y-339600D02*
D03*
X40441Y-343600D02*
D03*
Y-351600D02*
D03*
X38441Y-139600D02*
D03*
X36441Y-143600D02*
D03*
Y-151600D02*
D03*
Y-215600D02*
D03*
Y-223600D02*
D03*
X38441Y-227600D02*
D03*
X36441Y-231600D02*
D03*
X38441Y-235600D02*
D03*
Y-243600D02*
D03*
X36441Y-247600D02*
D03*
X38441Y-251600D02*
D03*
X36441Y-255600D02*
D03*
Y-327600D02*
D03*
X38441Y-331600D02*
D03*
X36441Y-335600D02*
D03*
X38441Y-339600D02*
D03*
X36441Y-343600D02*
D03*
Y-351600D02*
D03*
X34441Y-139600D02*
D03*
X32441Y-143600D02*
D03*
X34441Y-147600D02*
D03*
X32441Y-151600D02*
D03*
X34441Y-163600D02*
D03*
Y-219600D02*
D03*
Y-227600D02*
D03*
Y-235600D02*
D03*
Y-243600D02*
D03*
Y-251600D02*
D03*
Y-267600D02*
D03*
Y-275600D02*
D03*
Y-299600D02*
D03*
Y-307600D02*
D03*
Y-323600D02*
D03*
X32441Y-327600D02*
D03*
X34441Y-331600D02*
D03*
X32441Y-335600D02*
D03*
X34441Y-339600D02*
D03*
X32441Y-343600D02*
D03*
Y-351600D02*
D03*
X30441Y-139600D02*
D03*
X28441Y-143600D02*
D03*
X30441Y-147600D02*
D03*
X28441Y-151600D02*
D03*
X30441Y-163600D02*
D03*
X28441Y-167600D02*
D03*
Y-327600D02*
D03*
X30441Y-331600D02*
D03*
X28441Y-335600D02*
D03*
X30441Y-339600D02*
D03*
X28441Y-343600D02*
D03*
Y-351600D02*
D03*
X26441Y-139600D02*
D03*
X24441Y-143600D02*
D03*
X26441Y-147600D02*
D03*
X24441Y-151600D02*
D03*
X26441Y-163600D02*
D03*
X24441Y-167600D02*
D03*
Y-191600D02*
D03*
X26441Y-195600D02*
D03*
X24441Y-287600D02*
D03*
X26441Y-299600D02*
D03*
X24441Y-303600D02*
D03*
X26441Y-307600D02*
D03*
X24441Y-311600D02*
D03*
X26441Y-331600D02*
D03*
X24441Y-335600D02*
D03*
X26441Y-339600D02*
D03*
X24441Y-343600D02*
D03*
Y-351600D02*
D03*
X22441Y-139600D02*
D03*
X20441Y-143600D02*
D03*
X22441Y-147600D02*
D03*
X20441Y-151600D02*
D03*
X22441Y-163600D02*
D03*
X20441Y-167600D02*
D03*
X22441Y-171600D02*
D03*
X20441Y-191600D02*
D03*
X22441Y-195600D02*
D03*
X20441Y-199600D02*
D03*
Y-231600D02*
D03*
X22441Y-235600D02*
D03*
Y-243600D02*
D03*
X20441Y-247600D02*
D03*
X22441Y-251600D02*
D03*
X20441Y-255600D02*
D03*
X22441Y-259600D02*
D03*
Y-267600D02*
D03*
X20441Y-271600D02*
D03*
X22441Y-283600D02*
D03*
X20441Y-287600D02*
D03*
X22441Y-291600D02*
D03*
Y-299600D02*
D03*
X20441Y-303600D02*
D03*
X22441Y-307600D02*
D03*
X20441Y-311600D02*
D03*
X22441Y-323600D02*
D03*
X20441Y-335600D02*
D03*
X22441Y-339600D02*
D03*
X20441Y-343600D02*
D03*
Y-351600D02*
D03*
X18441Y-139600D02*
D03*
X16441Y-143600D02*
D03*
X18441Y-147600D02*
D03*
X16441Y-151600D02*
D03*
X18441Y-163600D02*
D03*
X16441Y-167600D02*
D03*
X18441Y-171600D02*
D03*
X16441Y-191600D02*
D03*
X18441Y-195600D02*
D03*
X16441Y-199600D02*
D03*
X18441Y-203600D02*
D03*
X16441Y-215600D02*
D03*
X18441Y-219600D02*
D03*
X16441Y-223600D02*
D03*
X18441Y-235600D02*
D03*
Y-243600D02*
D03*
X16441Y-247600D02*
D03*
X18441Y-251600D02*
D03*
X16441Y-255600D02*
D03*
X18441Y-259600D02*
D03*
Y-267600D02*
D03*
X16441Y-271600D02*
D03*
X18441Y-275600D02*
D03*
X16441Y-279600D02*
D03*
X18441Y-291600D02*
D03*
Y-299600D02*
D03*
X16441Y-303600D02*
D03*
X18441Y-307600D02*
D03*
X16441Y-311600D02*
D03*
X18441Y-323600D02*
D03*
X16441Y-327600D02*
D03*
X18441Y-339600D02*
D03*
X16441Y-343600D02*
D03*
Y-351600D02*
D03*
X14441Y-139600D02*
D03*
X12441Y-143600D02*
D03*
X14441Y-147600D02*
D03*
X12441Y-151600D02*
D03*
X14441Y-163600D02*
D03*
X12441Y-167600D02*
D03*
X14441Y-171600D02*
D03*
X12441Y-191600D02*
D03*
X14441Y-195600D02*
D03*
X12441Y-199600D02*
D03*
X14441Y-203600D02*
D03*
X12441Y-215600D02*
D03*
X14441Y-219600D02*
D03*
X12441Y-223600D02*
D03*
X14441Y-243600D02*
D03*
X12441Y-247600D02*
D03*
X14441Y-251600D02*
D03*
X12441Y-255600D02*
D03*
X14441Y-259600D02*
D03*
Y-267600D02*
D03*
X12441Y-271600D02*
D03*
X14441Y-275600D02*
D03*
X12441Y-279600D02*
D03*
X14441Y-291600D02*
D03*
Y-299600D02*
D03*
X12441Y-303600D02*
D03*
X14441Y-307600D02*
D03*
X12441Y-311600D02*
D03*
X14441Y-323600D02*
D03*
X12441Y-327600D02*
D03*
X14441Y-331600D02*
D03*
X12441Y-343600D02*
D03*
Y-351600D02*
D03*
X10441Y-139600D02*
D03*
Y-163600D02*
D03*
Y-171600D02*
D03*
X8441Y-191600D02*
D03*
X10441Y-195600D02*
D03*
Y-203600D02*
D03*
Y-227600D02*
D03*
Y-243600D02*
D03*
X8441Y-247600D02*
D03*
X10441Y-251600D02*
D03*
Y-259600D02*
D03*
Y-267600D02*
D03*
Y-275600D02*
D03*
X8441Y-279600D02*
D03*
X10441Y-299600D02*
D03*
Y-323600D02*
D03*
Y-331600D02*
D03*
X8441Y-351600D02*
D03*
X6441Y-139600D02*
D03*
X4441Y-191600D02*
D03*
X6441Y-243600D02*
D03*
X4441Y-351600D02*
D03*
X2441Y-243600D02*
D03*
X441Y-351600D02*
D03*
X-3559Y-191600D02*
D03*
X-1559Y-243600D02*
D03*
X-3559Y-351600D02*
D03*
X-5559Y-139600D02*
D03*
X-7559Y-143600D02*
D03*
Y-167600D02*
D03*
Y-191600D02*
D03*
Y-199600D02*
D03*
Y-223600D02*
D03*
X-5559Y-227600D02*
D03*
Y-243600D02*
D03*
X-7559Y-247600D02*
D03*
Y-279600D02*
D03*
X-5559Y-299600D02*
D03*
X-7559Y-303600D02*
D03*
Y-327600D02*
D03*
Y-351600D02*
D03*
X-9559Y-139600D02*
D03*
Y-171600D02*
D03*
X-11559Y-191600D02*
D03*
X-9559Y-195600D02*
D03*
Y-227600D02*
D03*
Y-243600D02*
D03*
X-11559Y-247600D02*
D03*
X-9559Y-251600D02*
D03*
Y-275600D02*
D03*
X-11559Y-279600D02*
D03*
X-9559Y-299600D02*
D03*
Y-331600D02*
D03*
X-11559Y-351600D02*
D03*
X-13559Y-139600D02*
D03*
X-15559Y-191600D02*
D03*
X-13559Y-243600D02*
D03*
X-15559Y-351600D02*
D03*
X-19559Y-263600D02*
D03*
Y-351600D02*
D03*
X-23559Y-159600D02*
D03*
Y-191600D02*
D03*
X-21559Y-211600D02*
D03*
X-23559Y-263600D02*
D03*
X-21559Y-315600D02*
D03*
X-23559Y-351600D02*
D03*
X-25559Y-139600D02*
D03*
Y-155600D02*
D03*
Y-211600D02*
D03*
Y-259600D02*
D03*
Y-267600D02*
D03*
Y-299600D02*
D03*
Y-315600D02*
D03*
X269685Y-136843D02*
D03*
X234252Y-133742D02*
D03*
X263779Y-106151D02*
D03*
X71850Y-147638D02*
D03*
X75787Y-131890D02*
D03*
X643701Y-63976D02*
D03*
X644685Y-45276D02*
D03*
X623000Y-37402D02*
D03*
X610236Y-8858D02*
D03*
X609252Y-26575D02*
D03*
X98425Y-102362D02*
D03*
X89567D02*
D03*
X85630Y-313976D02*
D03*
X86614Y-258858D02*
D03*
X81693Y-205709D02*
D03*
X86614Y-110236D02*
D03*
X360236Y-268586D02*
D03*
Y-272490D02*
D03*
X63976Y-227362D02*
D03*
X68898Y-285433D02*
D03*
X67913Y-340551D02*
D03*
X68573Y-179321D02*
D03*
X44291Y-252953D02*
D03*
Y-272638D02*
D03*
Y-326772D02*
D03*
Y-307087D02*
D03*
X26575Y-291339D02*
D03*
X31496Y-189961D02*
D03*
X44291Y-147638D02*
D03*
Y-167323D02*
D03*
Y-200787D02*
D03*
Y-220472D02*
D03*
X570727Y-105662D02*
D03*
X325787Y-243205D02*
D03*
Y-233362D02*
D03*
X103409Y-141732D02*
D03*
X103347Y-110236D02*
D03*
X119095Y-126047D02*
D03*
X494095Y-137647D02*
D03*
X518701Y-104214D02*
D03*
X519587Y-134596D02*
D03*
X528543Y-104214D02*
D03*
X625000Y-48080D02*
D03*
X658465Y-21899D02*
D03*
X625000Y-29773D02*
D03*
X114173Y-83088D02*
D03*
X441929Y-122883D02*
D03*
X256890Y-124852D02*
D03*
Y-121899D02*
D03*
X250000Y-120915D02*
D03*
X129921Y-79576D02*
D03*
X473425Y-125836D02*
D03*
X473425Y-123868D02*
D03*
X473425Y-121899D02*
D03*
X505905Y-137647D02*
D03*
X163071Y-390730D02*
D03*
X632432Y-132480D02*
D03*
X614321Y-118307D02*
D03*
X99410Y-50049D02*
D03*
X26495Y-8991D02*
D03*
X512657Y-270462D02*
D03*
X632432Y-141142D02*
D03*
X259285Y-390247D02*
D03*
X267204Y-390009D02*
D03*
X216162Y-390947D02*
D03*
X235144Y-390416D02*
D03*
X251456Y-390009D02*
D03*
X226063Y-390722D02*
D03*
X281201Y-390009D02*
D03*
X174941Y-390600D02*
D03*
X202441D02*
D03*
X538813Y-144506D02*
D03*
X544813Y-109806D02*
D03*
X566813Y-132405D02*
D03*
X555364Y-249410D02*
D03*
X544291Y-199655D02*
D03*
X509842Y-197687D02*
D03*
X544291Y-201624D02*
D03*
X509842Y-199655D02*
D03*
Y-201624D02*
D03*
X544291Y-197687D02*
D03*
X509842Y-195718D02*
D03*
X361811Y-207087D02*
D03*
X361417Y-203150D02*
D03*
X326969Y-197573D02*
D03*
X326966Y-195171D02*
D03*
X366535Y-202362D02*
D03*
X358661Y-194488D02*
D03*
X634252Y-314567D02*
D03*
X653150Y-314567D02*
D03*
X509391Y-350636D02*
D03*
X508997Y-335675D02*
D03*
X237402Y-133465D02*
D03*
X240945D02*
D03*
X447244Y-324852D02*
D03*
X451181D02*
D03*
X433858D02*
D03*
X460630D02*
D03*
X437795D02*
D03*
X431102D02*
D03*
X444488D02*
D03*
X457480D02*
D03*
X453937D02*
D03*
X440551D02*
D03*
X222638Y-374655D02*
D03*
X218445Y-374108D02*
D03*
X453937Y-306742D02*
D03*
X451181D02*
D03*
X267286Y-130697D02*
D03*
X109409Y-140111D02*
D03*
X105409D02*
D03*
X101409D02*
D03*
X97409D02*
D03*
X399618Y-136828D02*
D03*
X65945Y-57923D02*
D03*
X615158Y-8858D02*
D03*
X70866Y-122047D02*
D03*
X360204Y-252984D02*
D03*
X417596Y-175197D02*
D03*
X377921Y-203740D02*
D03*
X372016Y-200787D02*
D03*
X354541Y-223636D02*
D03*
X354452Y-235236D02*
D03*
X356578Y-225247D02*
D03*
X379921Y-201740D02*
D03*
X102528Y-211583D02*
D03*
X97125Y-219488D02*
D03*
X99410Y-216535D02*
D03*
X101378Y-214567D02*
D03*
X86614Y-175197D02*
D03*
X361652Y-235205D02*
D03*
X359131Y-223425D02*
D03*
X361531D02*
D03*
X360236Y-262186D02*
D03*
Y-266186D02*
D03*
X85416Y-317699D02*
D03*
X85630Y-263779D02*
D03*
X86562Y-211183D02*
D03*
X411043Y-174974D02*
D03*
X413440Y-174850D02*
D03*
X421596Y-175034D02*
D03*
X406528Y-157767D02*
D03*
X404528Y-163386D02*
D03*
X407480Y-160433D02*
D03*
X86614Y-221457D02*
D03*
X427165Y-175246D02*
D03*
X75787Y-232283D02*
D03*
X87167Y-166377D02*
D03*
X89567Y-166370D02*
D03*
X85630Y-213583D02*
D03*
Y-266179D02*
D03*
Y-320313D02*
D03*
X543276Y-226591D02*
D03*
X544294Y-224248D02*
D03*
X544291Y-233268D02*
D03*
X359252Y-235236D02*
D03*
X356852D02*
D03*
X407480Y-163386D02*
D03*
X47244Y-8858D02*
D03*
X40354D02*
D03*
X33465D02*
D03*
X26575Y19685D02*
D03*
X86614Y-227362D02*
D03*
X63976Y-221457D02*
D03*
X82677Y-232283D02*
D03*
X63976Y-275590D02*
D03*
X75787Y-285433D02*
D03*
X87598Y-275590D02*
D03*
Y-281496D02*
D03*
X81880Y-287582D02*
D03*
X62992Y-329724D02*
D03*
X74803Y-339567D02*
D03*
X78740Y-340551D02*
D03*
X87598Y-335630D02*
D03*
Y-329724D02*
D03*
X63976Y-179134D02*
D03*
X74803D02*
D03*
X86562Y-169257D02*
D03*
X80709Y-180118D02*
D03*
X26575Y-283465D02*
D03*
X30512Y-170276D02*
D03*
X323850Y-241173D02*
D03*
Y-237205D02*
D03*
X323819Y-231299D02*
D03*
X325787Y-229362D02*
D03*
X323819Y-227362D02*
D03*
X325787Y-239205D02*
D03*
X-23622Y-342520D02*
D03*
X89567Y-140270D02*
D03*
X87254Y-139629D02*
D03*
X119095Y-130047D02*
D03*
X117126Y-132047D02*
D03*
X107346Y-110236D02*
D03*
X105347Y-112205D02*
D03*
X99347Y-110236D02*
D03*
X109409Y-112236D02*
D03*
X119095Y-122047D02*
D03*
X-23622Y-229331D02*
D03*
Y-233268D02*
D03*
Y-237205D02*
D03*
Y-241142D02*
D03*
Y-282480D02*
D03*
Y-286417D02*
D03*
Y-290354D02*
D03*
Y-294291D02*
D03*
Y-335630D02*
D03*
Y-339567D02*
D03*
Y-346457D02*
D03*
X107409Y-141732D02*
D03*
X99410D02*
D03*
X-23622Y-70866D02*
D03*
Y-66929D02*
D03*
Y-62992D02*
D03*
Y-60039D02*
D03*
Y-102362D02*
D03*
Y-106299D02*
D03*
Y-110236D02*
D03*
Y-114173D02*
D03*
Y-187992D02*
D03*
Y-184055D02*
D03*
Y-181102D02*
D03*
Y-177165D02*
D03*
X117126Y-128047D02*
D03*
Y-124047D02*
D03*
Y-119921D02*
D03*
X101284Y-112205D02*
D03*
X97284D02*
D03*
X544291Y-195718D02*
D03*
X469521Y-137615D02*
D03*
X533878Y-117716D02*
D03*
X524606Y-125836D02*
D03*
X524557Y-128740D02*
D03*
X651557Y-64306D02*
D03*
X450850Y-174127D02*
D03*
X512795Y-104214D02*
D03*
X320866Y-272490D02*
D03*
X463551Y-116025D02*
D03*
X658465Y-37647D02*
D03*
Y-29773D02*
D03*
X625000Y-21899D02*
D03*
X190354Y-377411D02*
D03*
X412339Y-123805D02*
D03*
X424213Y-175246D02*
D03*
X314961Y-118947D02*
D03*
X430807Y-175344D02*
D03*
X309016Y-128659D02*
D03*
X418898Y-144143D02*
D03*
X405512Y-136611D02*
D03*
X416106Y-144180D02*
D03*
X398568Y-145083D02*
D03*
X210433Y-374655D02*
D03*
X206496D02*
D03*
X442126Y-306742D02*
D03*
X439370D02*
D03*
X237992Y-374655D02*
D03*
X241929D02*
D03*
X253655Y-374421D02*
D03*
X256890Y-374655D02*
D03*
X273425D02*
D03*
X269502Y-374291D02*
D03*
X246339Y-386975D02*
D03*
X249410Y-387253D02*
D03*
X232480D02*
D03*
X229331D02*
D03*
X436221Y-306742D02*
D03*
X212795Y-387253D02*
D03*
X433465Y-306742D02*
D03*
X215945Y-387253D02*
D03*
X262006Y-387255D02*
D03*
X448032Y-306742D02*
D03*
X265158Y-387253D02*
D03*
X445276Y-306742D02*
D03*
X104528Y-92175D02*
D03*
X269685Y-106151D02*
D03*
X244094Y-109104D02*
D03*
X475295Y-133612D02*
D03*
X505905Y-131742D02*
D03*
X131890Y-72687D02*
D03*
X179134Y-386466D02*
D03*
Y-389616D02*
D03*
X178543Y-377411D02*
D03*
X534400Y-126969D02*
D03*
X443898Y-175049D02*
D03*
X99410Y-65797D02*
D03*
Y-57923D02*
D03*
X65945Y-65797D02*
D03*
Y-50049D02*
D03*
X78740Y-238041D02*
D03*
X33465Y19833D02*
D03*
X40354Y19685D02*
D03*
X47244D02*
D03*
X483268Y-114025D02*
D03*
X492319Y-114970D02*
D03*
X487205Y-114057D02*
D03*
X456742Y-116043D02*
D03*
X464328Y-146397D02*
D03*
X469291Y-143848D02*
D03*
X461319Y-143750D02*
D03*
X267323Y-122883D02*
D03*
X457283Y-175147D02*
D03*
X469390D02*
D03*
X544291Y-215403D02*
D03*
X512402Y-261958D02*
D03*
Y-265108D02*
D03*
X512543Y-268065D02*
D03*
X437697Y-175246D02*
D03*
X433858D02*
D03*
X404823Y-175344D02*
D03*
X402264D02*
D03*
X237008Y-129576D02*
D03*
X309016Y-113986D02*
D03*
X193898Y-115009D02*
D03*
Y-119931D02*
D03*
X309055Y-123868D02*
D03*
X182677Y-386466D02*
D03*
X186614D02*
D03*
X182677Y-389616D02*
D03*
X186614D02*
D03*
D168*
X611417Y-227953D02*
D03*
Y-223228D02*
D03*
X604724Y-227953D02*
D03*
X598819Y-228346D02*
D03*
X604724Y-222835D02*
D03*
X599065Y-223031D02*
D03*
X576132Y-124606D02*
D03*
D169*
X564896Y-236697D02*
D03*
D170*
X651545Y-95108D02*
D03*
X413356Y7254D02*
D03*
Y-95108D02*
D03*
X651545Y7254D02*
D03*
X71880Y7412D02*
D03*
X310069Y-94950D02*
D03*
Y7412D02*
D03*
X71880Y-94950D02*
D03*
D171*
X99016Y-121653D02*
D03*
X103347D02*
D03*
X107677D02*
D03*
X99016Y-125984D02*
D03*
X103347D02*
D03*
X107677D02*
D03*
X99016Y-130315D02*
D03*
X103347D02*
D03*
X107677D02*
D03*
M02*
